(kicad_sch
	(version 20250114)
	(generator "eeschema")
	(generator_version "9.0")
	(paper "A3")
	(title_block
		(title "OCuLink to 10GbE adapter")
		(date "2026-02-23")
		(rev "1.1.0")
		(company "Antmicro Ltd")
		(comment 1 "www.antmicro.com")
	)
	(text "ICT Testpoints\nplace on bottom"
		(exclude_from_sim no)
		(at 236.22 173.228 0)
		(effects
			(font
				(size 1.27 1.27)
			)
		)
	)
	(text "X710-AT2 Power"
		(exclude_from_sim no)
		(at 215.9 38.1 0)
		(effects
			(font
				(size 2.54 2.54)
				(thickness 0.508)
				(bold yes)
			)
		)
	)
	(text_box "XGB_AVDDH Decoupling"
		(exclude_from_sim no)
		(at 16.51 83.82 0)
		(size 106.68 25.4)
		(margins 0.9525 0.9525 0.9525 0.9525)
		(stroke
			(width 0)
			(type solid)
		)
		(fill
			(type color)
			(color 255 255 194 0.2)
		)
		(effects
			(font
				(size 1.27 1.27)
			)
			(justify right top)
		)
	)
	(text_box "P0_AVDDL Decoupling"
		(exclude_from_sim no)
		(at 16.51 137.16 0)
		(size 106.68 25.4)
		(margins 0.9525 0.9525 0.9525 0.9525)
		(stroke
			(width 0)
			(type solid)
		)
		(fill
			(type color)
			(color 255 255 194 0.2)
		)
		(effects
			(font
				(size 1.27 1.27)
			)
			(justify right top)
		)
	)
	(text_box "XFI_VDD Decoupling"
		(exclude_from_sim no)
		(at 16.51 190.5 0)
		(size 106.68 25.4)
		(margins 0.9525 0.9525 0.9525 0.9525)
		(stroke
			(width 0)
			(type solid)
		)
		(fill
			(type color)
			(color 255 255 194 0.2)
		)
		(effects
			(font
				(size 1.27 1.27)
			)
			(justify right top)
		)
	)
	(text_box "AVDDH Decoupling"
		(exclude_from_sim no)
		(at 16.51 110.49 0)
		(size 106.68 25.4)
		(margins 0.9525 0.9525 0.9525 0.9525)
		(stroke
			(width 0)
			(type solid)
		)
		(fill
			(type color)
			(color 255 255 194 0.2)
		)
		(effects
			(font
				(size 1.27 1.27)
			)
			(justify right top)
		)
	)
	(text_box "XFI_PVDD Decoupling"
		(exclude_from_sim no)
		(at 16.51 217.17 0)
		(size 106.68 25.4)
		(margins 0.9525 0.9525 0.9525 0.9525)
		(stroke
			(width 0)
			(type solid)
		)
		(fill
			(type color)
			(color 255 255 194 0.2)
		)
		(effects
			(font
				(size 1.27 1.27)
			)
			(justify right top)
		)
	)
	(text_box "VCCD Decoupling"
		(exclude_from_sim no)
		(at 295.91 62.23 0)
		(size 109.22 38.1)
		(margins 0.9525 0.9525 0.9525 0.9525)
		(stroke
			(width 0)
			(type solid)
		)
		(fill
			(type color)
			(color 255 255 194 0.2)
		)
		(effects
			(font
				(size 1.27 1.27)
			)
			(justify right top)
		)
	)
	(text_box "DVDD Decoupling"
		(exclude_from_sim no)
		(at 16.51 40.64 0)
		(size 106.68 20.32)
		(margins 0.9525 0.9525 0.9525 0.9525)
		(stroke
			(width 0)
			(type solid)
		)
		(fill
			(type color)
			(color 255 255 194 0.2)
		)
		(effects
			(font
				(size 1.27 1.27)
			)
			(justify right top)
		)
	)
	(text_box "+3V3 Decoupling"
		(exclude_from_sim no)
		(at 295.91 101.6 0)
		(size 109.22 38.1)
		(margins 0.9525 0.9525 0.9525 0.9525)
		(stroke
			(width 0)
			(type solid)
		)
		(fill
			(type color)
			(color 255 255 194 0.2)
		)
		(effects
			(font
				(size 1.27 1.27)
			)
			(justify right top)
		)
	)
	(text_box "Place close\nto T2 pin"
		(exclude_from_sim no)
		(at 302.26 113.03 0)
		(size 7.62 8.89)
		(margins 0.9525 0.9525 0.9525 0.9525)
		(stroke
			(width 0)
			(type solid)
		)
		(fill
			(type none)
		)
		(effects
			(font
				(size 1.27 1.27)
			)
		)
	)
	(text_box "P1_AVDDL Decoupling"
		(exclude_from_sim no)
		(at 16.51 163.83 0)
		(size 106.68 25.4)
		(margins 0.9525 0.9525 0.9525 0.9525)
		(stroke
			(width 0)
			(type solid)
		)
		(fill
			(type color)
			(color 255 255 194 0.2)
		)
		(effects
			(font
				(size 1.27 1.27)
			)
			(justify right top)
		)
	)
	(text_box "+1V8 Decoupling (VDDIO1, VDDIO2)"
		(exclude_from_sim no)
		(at 16.51 62.23 0)
		(size 106.68 20.32)
		(margins 0.9525 0.9525 0.9525 0.9525)
		(stroke
			(width 0)
			(type solid)
		)
		(fill
			(type color)
			(color 255 255 194 0.2)
		)
		(effects
			(font
				(size 1.27 1.27)
			)
			(justify right top)
		)
	)
	(text_box "VCCA Decoupling"
		(exclude_from_sim no)
		(at 295.91 40.64 0)
		(size 109.22 20.32)
		(margins 0.9525 0.9525 0.9525 0.9525)
		(stroke
			(width 0)
			(type solid)
		)
		(fill
			(type color)
			(color 255 255 194 0.2)
		)
		(effects
			(font
				(size 1.27 1.27)
			)
			(justify right top)
		)
	)
	(text_box "PLL_VDD Decoupling"
		(exclude_from_sim no)
		(at 16.51 243.84 0)
		(size 106.68 25.4)
		(margins 0.9525 0.9525 0.9525 0.9525)
		(stroke
			(width 0)
			(type solid)
		)
		(fill
			(type color)
			(color 255 255 194 0.2)
		)
		(effects
			(font
				(size 1.27 1.27)
			)
			(justify right top)
		)
	)
	(junction
		(at 370.84 123.19)
		(diameter 0)
		(color 0 0 0 0)
	)
	(junction
		(at 214.63 95.25)
		(diameter 0)
		(color 0 0 0 0)
	)
	(junction
		(at 62.23 172.72)
		(diameter 0)
		(color 0 0 0 0)
	)
	(junction
		(at 41.91 172.72)
		(diameter 0)
		(color 0 0 0 0)
	)
	(junction
		(at 106.68 172.72)
		(diameter 0)
		(color 0 0 0 0)
	)
	(junction
		(at 115.57 66.04)
		(diameter 0)
		(color 0 0 0 0)
	)
	(junction
		(at 97.79 66.04)
		(diameter 0)
		(color 0 0 0 0)
	)
	(junction
		(at 379.73 44.45)
		(diameter 0)
		(color 0 0 0 0)
	)
	(junction
		(at 66.04 119.38)
		(diameter 0)
		(color 0 0 0 0)
	)
	(junction
		(at 54.61 226.06)
		(diameter 0)
		(color 0 0 0 0)
	)
	(junction
		(at 270.51 138.43)
		(diameter 0)
		(color 0 0 0 0)
	)
	(junction
		(at 53.34 44.45)
		(diameter 0)
		(color 0 0 0 0)
	)
	(junction
		(at 39.37 252.73)
		(diameter 0)
		(color 0 0 0 0)
	)
	(junction
		(at 71.12 146.05)
		(diameter 0)
		(color 0 0 0 0)
	)
	(junction
		(at 270.51 105.41)
		(diameter 0)
		(color 0 0 0 0)
	)
	(junction
		(at 344.17 44.45)
		(diameter 0)
		(color 0 0 0 0)
	)
	(junction
		(at 326.39 123.19)
		(diameter 0)
		(color 0 0 0 0)
	)
	(junction
		(at 283.21 142.24)
		(diameter 0)
		(color 0 0 0 0)
	)
	(junction
		(at 361.95 105.41)
		(diameter 0)
		(color 0 0 0 0)
	)
	(junction
		(at 283.21 118.11)
		(diameter 0)
		(color 0 0 0 0)
	)
	(junction
		(at 388.62 83.82)
		(diameter 0)
		(color 0 0 0 0)
	)
	(junction
		(at 335.28 66.04)
		(diameter 0)
		(color 0 0 0 0)
	)
	(junction
		(at 66.04 226.06)
		(diameter 0)
		(color 0 0 0 0)
	)
	(junction
		(at 299.72 105.41)
		(diameter 0)
		(color 0 0 0 0)
	)
	(junction
		(at 44.45 44.45)
		(diameter 0)
		(color 0 0 0 0)
	)
	(junction
		(at 80.01 44.45)
		(diameter 0)
		(color 0 0 0 0)
	)
	(junction
		(at 361.95 123.19)
		(diameter 0)
		(color 0 0 0 0)
	)
	(junction
		(at 31.75 146.05)
		(diameter 0)
		(color 0 0 0 0)
	)
	(junction
		(at 214.63 97.79)
		(diameter 0)
		(color 0 0 0 0)
	)
	(junction
		(at 299.72 83.82)
		(diameter 0)
		(color 0 0 0 0)
	)
	(junction
		(at 299.72 66.04)
		(diameter 0)
		(color 0 0 0 0)
	)
	(junction
		(at 353.06 44.45)
		(diameter 0)
		(color 0 0 0 0)
	)
	(junction
		(at 71.12 172.72)
		(diameter 0)
		(color 0 0 0 0)
	)
	(junction
		(at 326.39 44.45)
		(diameter 0)
		(color 0 0 0 0)
	)
	(junction
		(at 54.61 252.73)
		(diameter 0)
		(color 0 0 0 0)
	)
	(junction
		(at 207.01 95.25)
		(diameter 0)
		(color 0 0 0 0)
	)
	(junction
		(at 317.5 66.04)
		(diameter 0)
		(color 0 0 0 0)
	)
	(junction
		(at 353.06 83.82)
		(diameter 0)
		(color 0 0 0 0)
	)
	(junction
		(at 335.28 105.41)
		(diameter 0)
		(color 0 0 0 0)
	)
	(junction
		(at 115.57 172.72)
		(diameter 0)
		(color 0 0 0 0)
	)
	(junction
		(at 308.61 123.19)
		(diameter 0)
		(color 0 0 0 0)
	)
	(junction
		(at 353.06 123.19)
		(diameter 0)
		(color 0 0 0 0)
	)
	(junction
		(at 308.61 83.82)
		(diameter 0)
		(color 0 0 0 0)
	)
	(junction
		(at 97.79 44.45)
		(diameter 0)
		(color 0 0 0 0)
	)
	(junction
		(at 66.04 199.39)
		(diameter 0)
		(color 0 0 0 0)
	)
	(junction
		(at 41.91 92.71)
		(diameter 0)
		(color 0 0 0 0)
	)
	(junction
		(at 344.17 66.04)
		(diameter 0)
		(color 0 0 0 0)
	)
	(junction
		(at 186.69 110.49)
		(diameter 0)
		(color 0 0 0 0)
	)
	(junction
		(at 66.04 146.05)
		(diameter 0)
		(color 0 0 0 0)
	)
	(junction
		(at 66.04 252.73)
		(diameter 0)
		(color 0 0 0 0)
	)
	(junction
		(at 135.89 140.97)
		(diameter 0)
		(color 0 0 0 0)
	)
	(junction
		(at 214.63 113.03)
		(diameter 0)
		(color 0 0 0 0)
	)
	(junction
		(at 379.73 123.19)
		(diameter 0)
		(color 0 0 0 0)
	)
	(junction
		(at 97.79 119.38)
		(diameter 0)
		(color 0 0 0 0)
	)
	(junction
		(at 283.21 105.41)
		(diameter 0)
		(color 0 0 0 0)
	)
	(junction
		(at 270.51 143.51)
		(diameter 0)
		(color 0 0 0 0)
	)
	(junction
		(at 67.31 92.71)
		(diameter 0)
		(color 0 0 0 0)
	)
	(junction
		(at 39.37 199.39)
		(diameter 0)
		(color 0 0 0 0)
	)
	(junction
		(at 299.72 44.45)
		(diameter 0)
		(color 0 0 0 0)
	)
	(junction
		(at 293.37 83.82)
		(diameter 0)
		(color 0 0 0 0)
	)
	(junction
		(at 106.68 146.05)
		(diameter 0)
		(color 0 0 0 0)
	)
	(junction
		(at 53.34 146.05)
		(diameter 0)
		(color 0 0 0 0)
	)
	(junction
		(at 353.06 105.41)
		(diameter 0)
		(color 0 0 0 0)
	)
	(junction
		(at 88.9 119.38)
		(diameter 0)
		(color 0 0 0 0)
	)
	(junction
		(at 361.95 44.45)
		(diameter 0)
		(color 0 0 0 0)
	)
	(junction
		(at 156.21 130.81)
		(diameter 0)
		(color 0 0 0 0)
	)
	(junction
		(at 62.23 44.45)
		(diameter 0)
		(color 0 0 0 0)
	)
	(junction
		(at 379.73 83.82)
		(diameter 0)
		(color 0 0 0 0)
	)
	(junction
		(at 326.39 105.41)
		(diameter 0)
		(color 0 0 0 0)
	)
	(junction
		(at 317.5 105.41)
		(diameter 0)
		(color 0 0 0 0)
	)
	(junction
		(at 97.79 172.72)
		(diameter 0)
		(color 0 0 0 0)
	)
	(junction
		(at 326.39 66.04)
		(diameter 0)
		(color 0 0 0 0)
	)
	(junction
		(at 115.57 119.38)
		(diameter 0)
		(color 0 0 0 0)
	)
	(junction
		(at 106.68 44.45)
		(diameter 0)
		(color 0 0 0 0)
	)
	(junction
		(at 88.9 172.72)
		(diameter 0)
		(color 0 0 0 0)
	)
	(junction
		(at 317.5 123.19)
		(diameter 0)
		(color 0 0 0 0)
	)
	(junction
		(at 214.63 90.17)
		(diameter 0)
		(color 0 0 0 0)
	)
	(junction
		(at 270.51 107.95)
		(diameter 0)
		(color 0 0 0 0)
	)
	(junction
		(at 62.23 66.04)
		(diameter 0)
		(color 0 0 0 0)
	)
	(junction
		(at 115.57 146.05)
		(diameter 0)
		(color 0 0 0 0)
	)
	(junction
		(at 335.28 83.82)
		(diameter 0)
		(color 0 0 0 0)
	)
	(junction
		(at 270.51 110.49)
		(diameter 0)
		(color 0 0 0 0)
	)
	(junction
		(at 53.34 92.71)
		(diameter 0)
		(color 0 0 0 0)
	)
	(junction
		(at 106.68 66.04)
		(diameter 0)
		(color 0 0 0 0)
	)
	(junction
		(at 115.57 44.45)
		(diameter 0)
		(color 0 0 0 0)
	)
	(junction
		(at 317.5 83.82)
		(diameter 0)
		(color 0 0 0 0)
	)
	(junction
		(at 31.75 172.72)
		(diameter 0)
		(color 0 0 0 0)
	)
	(junction
		(at 293.37 105.41)
		(diameter 0)
		(color 0 0 0 0)
	)
	(junction
		(at 388.62 44.45)
		(diameter 0)
		(color 0 0 0 0)
	)
	(junction
		(at 270.51 140.97)
		(diameter 0)
		(color 0 0 0 0)
	)
	(junction
		(at 270.51 90.17)
		(diameter 0)
		(color 0 0 0 0)
	)
	(junction
		(at 146.05 135.89)
		(diameter 0)
		(color 0 0 0 0)
	)
	(junction
		(at 88.9 66.04)
		(diameter 0)
		(color 0 0 0 0)
	)
	(junction
		(at 54.61 199.39)
		(diameter 0)
		(color 0 0 0 0)
	)
	(junction
		(at 53.34 172.72)
		(diameter 0)
		(color 0 0 0 0)
	)
	(junction
		(at 21.59 146.05)
		(diameter 0)
		(color 0 0 0 0)
	)
	(junction
		(at 388.62 66.04)
		(diameter 0)
		(color 0 0 0 0)
	)
	(junction
		(at 80.01 119.38)
		(diameter 0)
		(color 0 0 0 0)
	)
	(junction
		(at 97.79 199.39)
		(diameter 0)
		(color 0 0 0 0)
	)
	(junction
		(at 196.85 105.41)
		(diameter 0)
		(color 0 0 0 0)
	)
	(junction
		(at 270.51 97.79)
		(diameter 0)
		(color 0 0 0 0)
	)
	(junction
		(at 115.57 199.39)
		(diameter 0)
		(color 0 0 0 0)
	)
	(junction
		(at 276.86 95.25)
		(diameter 0)
		(color 0 0 0 0)
	)
	(junction
		(at 41.91 146.05)
		(diameter 0)
		(color 0 0 0 0)
	)
	(junction
		(at 344.17 105.41)
		(diameter 0)
		(color 0 0 0 0)
	)
	(junction
		(at 106.68 119.38)
		(diameter 0)
		(color 0 0 0 0)
	)
	(junction
		(at 88.9 44.45)
		(diameter 0)
		(color 0 0 0 0)
	)
	(junction
		(at 270.51 133.35)
		(diameter 0)
		(color 0 0 0 0)
	)
	(junction
		(at 66.04 172.72)
		(diameter 0)
		(color 0 0 0 0)
	)
	(junction
		(at 106.68 199.39)
		(diameter 0)
		(color 0 0 0 0)
	)
	(junction
		(at 176.53 120.65)
		(diameter 0)
		(color 0 0 0 0)
	)
	(junction
		(at 326.39 83.82)
		(diameter 0)
		(color 0 0 0 0)
	)
	(junction
		(at 97.79 146.05)
		(diameter 0)
		(color 0 0 0 0)
	)
	(junction
		(at 62.23 146.05)
		(diameter 0)
		(color 0 0 0 0)
	)
	(junction
		(at 39.37 226.06)
		(diameter 0)
		(color 0 0 0 0)
	)
	(junction
		(at 41.91 119.38)
		(diameter 0)
		(color 0 0 0 0)
	)
	(junction
		(at 299.72 123.19)
		(diameter 0)
		(color 0 0 0 0)
	)
	(junction
		(at 270.51 135.89)
		(diameter 0)
		(color 0 0 0 0)
	)
	(junction
		(at 379.73 66.04)
		(diameter 0)
		(color 0 0 0 0)
	)
	(junction
		(at 370.84 83.82)
		(diameter 0)
		(color 0 0 0 0)
	)
	(junction
		(at 344.17 123.19)
		(diameter 0)
		(color 0 0 0 0)
	)
	(junction
		(at 370.84 44.45)
		(diameter 0)
		(color 0 0 0 0)
	)
	(junction
		(at 115.57 226.06)
		(diameter 0)
		(color 0 0 0 0)
	)
	(junction
		(at 308.61 66.04)
		(diameter 0)
		(color 0 0 0 0)
	)
	(junction
		(at 361.95 66.04)
		(diameter 0)
		(color 0 0 0 0)
	)
	(junction
		(at 361.95 83.82)
		(diameter 0)
		(color 0 0 0 0)
	)
	(junction
		(at 300.99 142.24)
		(diameter 0)
		(color 0 0 0 0)
	)
	(junction
		(at 88.9 146.05)
		(diameter 0)
		(color 0 0 0 0)
	)
	(junction
		(at 62.23 119.38)
		(diameter 0)
		(color 0 0 0 0)
	)
	(junction
		(at 214.63 110.49)
		(diameter 0)
		(color 0 0 0 0)
	)
	(junction
		(at 53.34 119.38)
		(diameter 0)
		(color 0 0 0 0)
	)
	(junction
		(at 317.5 44.45)
		(diameter 0)
		(color 0 0 0 0)
	)
	(junction
		(at 370.84 66.04)
		(diameter 0)
		(color 0 0 0 0)
	)
	(junction
		(at 88.9 199.39)
		(diameter 0)
		(color 0 0 0 0)
	)
	(junction
		(at 335.28 44.45)
		(diameter 0)
		(color 0 0 0 0)
	)
	(junction
		(at 289.56 142.24)
		(diameter 0)
		(color 0 0 0 0)
	)
	(junction
		(at 292.1 142.24)
		(diameter 0)
		(color 0 0 0 0)
	)
	(junction
		(at 353.06 66.04)
		(diameter 0)
		(color 0 0 0 0)
	)
	(junction
		(at 166.37 125.73)
		(diameter 0)
		(color 0 0 0 0)
	)
	(junction
		(at 308.61 44.45)
		(diameter 0)
		(color 0 0 0 0)
	)
	(junction
		(at 270.51 95.25)
		(diameter 0)
		(color 0 0 0 0)
	)
	(no_connect
		(at 267.97 125.73)
	)
	(no_connect
		(at 267.97 123.19)
	)
	(wire
		(pts
			(xy 54.61 233.68) (xy 54.61 236.22)
		)
		(stroke
			(width 0)
			(type default)
		)
	)
	(wire
		(pts
			(xy 106.68 153.67) (xy 106.68 156.21)
		)
		(stroke
			(width 0)
			(type default)
		)
	)
	(wire
		(pts
			(xy 21.59 226.06) (xy 39.37 226.06)
		)
		(stroke
			(width 0)
			(type default)
		)
	)
	(wire
		(pts
			(xy 214.63 113.03) (xy 214.63 115.57)
		)
		(stroke
			(width 0)
			(type default)
		)
	)
	(wire
		(pts
			(xy 370.84 66.04) (xy 379.73 66.04)
		)
		(stroke
			(width 0)
			(type default)
		)
	)
	(wire
		(pts
			(xy 299.72 66.04) (xy 308.61 66.04)
		)
		(stroke
			(width 0)
			(type default)
		)
	)
	(wire
		(pts
			(xy 41.91 119.38) (xy 41.91 121.92)
		)
		(stroke
			(width 0)
			(type default)
		)
	)
	(wire
		(pts
			(xy 71.12 146.05) (xy 88.9 146.05)
		)
		(stroke
			(width 0)
			(type default)
		)
	)
	(wire
		(pts
			(xy 353.06 44.45) (xy 361.95 44.45)
		)
		(stroke
			(width 0)
			(type default)
		)
	)
	(wire
		(pts
			(xy 276.86 95.25) (xy 276.86 78.74)
		)
		(stroke
			(width 0)
			(type default)
		)
	)
	(wire
		(pts
			(xy 106.68 73.66) (xy 106.68 76.2)
		)
		(stroke
			(width 0)
			(type default)
		)
	)
	(wire
		(pts
			(xy 293.37 66.04) (xy 293.37 83.82)
		)
		(stroke
			(width 0)
			(type default)
		)
	)
	(wire
		(pts
			(xy 317.5 83.82) (xy 326.39 83.82)
		)
		(stroke
			(width 0)
			(type default)
		)
	)
	(wire
		(pts
			(xy 80.01 46.99) (xy 80.01 44.45)
		)
		(stroke
			(width 0)
			(type default)
		)
	)
	(wire
		(pts
			(xy 97.79 201.93) (xy 97.79 199.39)
		)
		(stroke
			(width 0)
			(type default)
		)
	)
	(wire
		(pts
			(xy 207.01 95.25) (xy 214.63 95.25)
		)
		(stroke
			(width 0)
			(type default)
		)
	)
	(wire
		(pts
			(xy 97.79 66.04) (xy 97.79 68.58)
		)
		(stroke
			(width 0)
			(type default)
		)
	)
	(wire
		(pts
			(xy 21.59 143.51) (xy 21.59 146.05)
		)
		(stroke
			(width 0)
			(type default)
		)
	)
	(wire
		(pts
			(xy 21.59 223.52) (xy 21.59 226.06)
		)
		(stroke
			(width 0)
			(type default)
		)
	)
	(wire
		(pts
			(xy 344.17 105.41) (xy 353.06 105.41)
		)
		(stroke
			(width 0)
			(type default)
		)
	)
	(wire
		(pts
			(xy 214.63 90.17) (xy 128.27 90.17)
		)
		(stroke
			(width 0)
			(type default)
		)
	)
	(wire
		(pts
			(xy 39.37 226.06) (xy 39.37 228.6)
		)
		(stroke
			(width 0)
			(type default)
		)
	)
	(wire
		(pts
			(xy 308.61 44.45) (xy 317.5 44.45)
		)
		(stroke
			(width 0)
			(type default)
		)
	)
	(wire
		(pts
			(xy 128.27 90.17) (xy 128.27 44.45)
		)
		(stroke
			(width 0)
			(type default)
		)
	)
	(wire
		(pts
			(xy 353.06 91.44) (xy 353.06 93.98)
		)
		(stroke
			(width 0)
			(type default)
		)
	)
	(wire
		(pts
			(xy 115.57 68.58) (xy 115.57 66.04)
		)
		(stroke
			(width 0)
			(type default)
		)
	)
	(wire
		(pts
			(xy 267.97 110.49) (xy 270.51 110.49)
		)
		(stroke
			(width 0)
			(type default)
		)
	)
	(wire
		(pts
			(xy 370.84 107.95) (xy 370.84 105.41)
		)
		(stroke
			(width 0)
			(type default)
		)
	)
	(wire
		(pts
			(xy 270.51 97.79) (xy 270.51 100.33)
		)
		(stroke
			(width 0)
			(type default)
		)
	)
	(wire
		(pts
			(xy 388.62 91.44) (xy 388.62 93.98)
		)
		(stroke
			(width 0)
			(type default)
		)
	)
	(wire
		(pts
			(xy 361.95 130.81) (xy 361.95 133.35)
		)
		(stroke
			(width 0)
			(type default)
		)
	)
	(wire
		(pts
			(xy 53.34 95.25) (xy 53.34 92.71)
		)
		(stroke
			(width 0)
			(type default)
		)
	)
	(wire
		(pts
			(xy 317.5 52.07) (xy 317.5 54.61)
		)
		(stroke
			(width 0)
			(type default)
		)
	)
	(wire
		(pts
			(xy 292.1 152.4) (xy 292.1 149.86)
		)
		(stroke
			(width 0)
			(type default)
		)
	)
	(wire
		(pts
			(xy 130.81 130.81) (xy 130.81 199.39)
		)
		(stroke
			(width 0)
			(type default)
		)
	)
	(wire
		(pts
			(xy 370.84 86.36) (xy 370.84 83.82)
		)
		(stroke
			(width 0)
			(type default)
		)
	)
	(wire
		(pts
			(xy 39.37 226.06) (xy 44.45 226.06)
		)
		(stroke
			(width 0)
			(type default)
		)
	)
	(wire
		(pts
			(xy 283.21 105.41) (xy 270.51 105.41)
		)
		(stroke
			(width 0)
			(type default)
		)
	)
	(wire
		(pts
			(xy 21.59 199.39) (xy 39.37 199.39)
		)
		(stroke
			(width 0)
			(type default)
		)
	)
	(wire
		(pts
			(xy 388.62 125.73) (xy 388.62 123.19)
		)
		(stroke
			(width 0)
			(type default)
		)
	)
	(wire
		(pts
			(xy 67.31 91.44) (xy 67.31 92.71)
		)
		(stroke
			(width 0)
			(type default)
		)
	)
	(wire
		(pts
			(xy 317.5 91.44) (xy 317.5 93.98)
		)
		(stroke
			(width 0)
			(type default)
		)
	)
	(wire
		(pts
			(xy 361.95 44.45) (xy 370.84 44.45)
		)
		(stroke
			(width 0)
			(type default)
		)
	)
	(wire
		(pts
			(xy 62.23 119.38) (xy 66.04 119.38)
		)
		(stroke
			(width 0)
			(type default)
		)
	)
	(wire
		(pts
			(xy 115.57 172.72) (xy 128.27 172.72)
		)
		(stroke
			(width 0)
			(type default)
		)
	)
	(wire
		(pts
			(xy 388.62 86.36) (xy 388.62 83.82)
		)
		(stroke
			(width 0)
			(type default)
		)
	)
	(wire
		(pts
			(xy 80.01 121.92) (xy 80.01 119.38)
		)
		(stroke
			(width 0)
			(type default)
		)
	)
	(wire
		(pts
			(xy 130.81 199.39) (xy 115.57 199.39)
		)
		(stroke
			(width 0)
			(type default)
		)
	)
	(wire
		(pts
			(xy 379.73 68.58) (xy 379.73 66.04)
		)
		(stroke
			(width 0)
			(type default)
		)
	)
	(wire
		(pts
			(xy 62.23 119.38) (xy 53.34 119.38)
		)
		(stroke
			(width 0)
			(type default)
		)
	)
	(wire
		(pts
			(xy 267.97 140.97) (xy 270.51 140.97)
		)
		(stroke
			(width 0)
			(type default)
		)
	)
	(wire
		(pts
			(xy 128.27 125.73) (xy 128.27 172.72)
		)
		(stroke
			(width 0)
			(type default)
		)
	)
	(wire
		(pts
			(xy 21.59 196.85) (xy 21.59 199.39)
		)
		(stroke
			(width 0)
			(type default)
		)
	)
	(wire
		(pts
			(xy 106.68 66.04) (xy 106.68 68.58)
		)
		(stroke
			(width 0)
			(type default)
		)
	)
	(wire
		(pts
			(xy 66.04 198.12) (xy 66.04 199.39)
		)
		(stroke
			(width 0)
			(type default)
		)
	)
	(wire
		(pts
			(xy 115.57 172.72) (xy 115.57 175.26)
		)
		(stroke
			(width 0)
			(type default)
		)
	)
	(wire
		(pts
			(xy 62.23 46.99) (xy 62.23 44.45)
		)
		(stroke
			(width 0)
			(type default)
		)
	)
	(wire
		(pts
			(xy 176.53 78.74) (xy 176.53 120.65)
		)
		(stroke
			(width 0)
			(type default)
		)
	)
	(wire
		(pts
			(xy 80.01 44.45) (xy 88.9 44.45)
		)
		(stroke
			(width 0)
			(type default)
		)
	)
	(wire
		(pts
			(xy 379.73 44.45) (xy 388.62 44.45)
		)
		(stroke
			(width 0)
			(type default)
		)
	)
	(wire
		(pts
			(xy 335.28 105.41) (xy 344.17 105.41)
		)
		(stroke
			(width 0)
			(type default)
		)
	)
	(wire
		(pts
			(xy 31.75 153.67) (xy 31.75 156.21)
		)
		(stroke
			(width 0)
			(type default)
		)
	)
	(wire
		(pts
			(xy 270.51 95.25) (xy 276.86 95.25)
		)
		(stroke
			(width 0)
			(type default)
		)
	)
	(wire
		(pts
			(xy 361.95 123.19) (xy 370.84 123.19)
		)
		(stroke
			(width 0)
			(type default)
		)
	)
	(wire
		(pts
			(xy 88.9 199.39) (xy 66.04 199.39)
		)
		(stroke
			(width 0)
			(type default)
		)
	)
	(wire
		(pts
			(xy 299.72 91.44) (xy 299.72 93.98)
		)
		(stroke
			(width 0)
			(type default)
		)
	)
	(wire
		(pts
			(xy 293.37 66.04) (xy 299.72 66.04)
		)
		(stroke
			(width 0)
			(type default)
		)
	)
	(wire
		(pts
			(xy 270.51 135.89) (xy 270.51 138.43)
		)
		(stroke
			(width 0)
			(type default)
		)
	)
	(wire
		(pts
			(xy 106.68 44.45) (xy 115.57 44.45)
		)
		(stroke
			(width 0)
			(type default)
		)
	)
	(wire
		(pts
			(xy 299.72 44.45) (xy 308.61 44.45)
		)
		(stroke
			(width 0)
			(type default)
		)
	)
	(wire
		(pts
			(xy 186.69 110.49) (xy 214.63 110.49)
		)
		(stroke
			(width 0)
			(type default)
		)
	)
	(wire
		(pts
			(xy 214.63 100.33) (xy 214.63 97.79)
		)
		(stroke
			(width 0)
			(type default)
		)
	)
	(wire
		(pts
			(xy 308.61 130.81) (xy 308.61 133.35)
		)
		(stroke
			(width 0)
			(type default)
		)
	)
	(wire
		(pts
			(xy 207.01 78.74) (xy 207.01 95.25)
		)
		(stroke
			(width 0)
			(type default)
		)
	)
	(wire
		(pts
			(xy 115.57 121.92) (xy 115.57 119.38)
		)
		(stroke
			(width 0)
			(type default)
		)
	)
	(wire
		(pts
			(xy 115.57 44.45) (xy 115.57 46.99)
		)
		(stroke
			(width 0)
			(type default)
		)
	)
	(wire
		(pts
			(xy 270.51 138.43) (xy 270.51 140.97)
		)
		(stroke
			(width 0)
			(type default)
		)
	)
	(wire
		(pts
			(xy 326.39 68.58) (xy 326.39 66.04)
		)
		(stroke
			(width 0)
			(type default)
		)
	)
	(wire
		(pts
			(xy 388.62 66.04) (xy 397.51 66.04)
		)
		(stroke
			(width 0)
			(type default)
		)
	)
	(wire
		(pts
			(xy 31.75 180.34) (xy 31.75 182.88)
		)
		(stroke
			(width 0)
			(type default)
		)
	)
	(wire
		(pts
			(xy 88.9 146.05) (xy 97.79 146.05)
		)
		(stroke
			(width 0)
			(type default)
		)
	)
	(wire
		(pts
			(xy 41.91 172.72) (xy 45.72 172.72)
		)
		(stroke
			(width 0)
			(type default)
		)
	)
	(wire
		(pts
			(xy 326.39 83.82) (xy 335.28 83.82)
		)
		(stroke
			(width 0)
			(type default)
		)
	)
	(wire
		(pts
			(xy 88.9 76.2) (xy 88.9 73.66)
		)
		(stroke
			(width 0)
			(type default)
		)
	)
	(wire
		(pts
			(xy 66.04 119.38) (xy 80.01 119.38)
		)
		(stroke
			(width 0)
			(type default)
		)
	)
	(wire
		(pts
			(xy 115.57 52.07) (xy 115.57 54.61)
		)
		(stroke
			(width 0)
			(type default)
		)
	)
	(wire
		(pts
			(xy 379.73 130.81) (xy 379.73 133.35)
		)
		(stroke
			(width 0)
			(type default)
		)
	)
	(wire
		(pts
			(xy 62.23 127) (xy 62.23 129.54)
		)
		(stroke
			(width 0)
			(type default)
		)
	)
	(wire
		(pts
			(xy 66.04 171.45) (xy 66.04 172.72)
		)
		(stroke
			(width 0)
			(type default)
		)
	)
	(wire
		(pts
			(xy 33.02 46.99) (xy 33.02 44.45)
		)
		(stroke
			(width 0)
			(type default)
		)
	)
	(wire
		(pts
			(xy 115.57 127) (xy 115.57 129.54)
		)
		(stroke
			(width 0)
			(type default)
		)
	)
	(wire
		(pts
			(xy 97.79 148.59) (xy 97.79 146.05)
		)
		(stroke
			(width 0)
			(type default)
		)
	)
	(wire
		(pts
			(xy 54.61 226.06) (xy 66.04 226.06)
		)
		(stroke
			(width 0)
			(type default)
		)
	)
	(wire
		(pts
			(xy 370.84 125.73) (xy 370.84 123.19)
		)
		(stroke
			(width 0)
			(type default)
		)
	)
	(wire
		(pts
			(xy 115.57 44.45) (xy 128.27 44.45)
		)
		(stroke
			(width 0)
			(type default)
		)
	)
	(wire
		(pts
			(xy 344.17 46.99) (xy 344.17 44.45)
		)
		(stroke
			(width 0)
			(type default)
		)
	)
	(wire
		(pts
			(xy 115.57 199.39) (xy 106.68 199.39)
		)
		(stroke
			(width 0)
			(type default)
		)
	)
	(wire
		(pts
			(xy 388.62 52.07) (xy 388.62 54.61)
		)
		(stroke
			(width 0)
			(type default)
		)
	)
	(wire
		(pts
			(xy 50.8 172.72) (xy 53.34 172.72)
		)
		(stroke
			(width 0)
			(type default)
		)
	)
	(wire
		(pts
			(xy 80.01 119.38) (xy 88.9 119.38)
		)
		(stroke
			(width 0)
			(type default)
		)
	)
	(wire
		(pts
			(xy 196.85 105.41) (xy 217.17 105.41)
		)
		(stroke
			(width 0)
			(type default)
		)
	)
	(wire
		(pts
			(xy 71.12 148.59) (xy 71.12 146.05)
		)
		(stroke
			(width 0)
			(type default)
		)
	)
	(wire
		(pts
			(xy 270.51 133.35) (xy 270.51 135.89)
		)
		(stroke
			(width 0)
			(type default)
		)
	)
	(wire
		(pts
			(xy 62.23 121.92) (xy 62.23 119.38)
		)
		(stroke
			(width 0)
			(type default)
		)
	)
	(wire
		(pts
			(xy 344.17 44.45) (xy 353.06 44.45)
		)
		(stroke
			(width 0)
			(type default)
		)
	)
	(wire
		(pts
			(xy 270.51 90.17) (xy 290.83 90.17)
		)
		(stroke
			(width 0)
			(type default)
		)
	)
	(wire
		(pts
			(xy 156.21 130.81) (xy 156.21 78.74)
		)
		(stroke
			(width 0)
			(type default)
		)
	)
	(wire
		(pts
			(xy 62.23 68.58) (xy 62.23 66.04)
		)
		(stroke
			(width 0)
			(type default)
		)
	)
	(wire
		(pts
			(xy 62.23 172.72) (xy 66.04 172.72)
		)
		(stroke
			(width 0)
			(type default)
		)
	)
	(wire
		(pts
			(xy 344.17 68.58) (xy 344.17 66.04)
		)
		(stroke
			(width 0)
			(type default)
		)
	)
	(wire
		(pts
			(xy 115.57 146.05) (xy 125.73 146.05)
		)
		(stroke
			(width 0)
			(type default)
		)
	)
	(wire
		(pts
			(xy 106.68 175.26) (xy 106.68 172.72)
		)
		(stroke
			(width 0)
			(type default)
		)
	)
	(wire
		(pts
			(xy 44.45 44.45) (xy 53.34 44.45)
		)
		(stroke
			(width 0)
			(type default)
		)
	)
	(wire
		(pts
			(xy 217.17 140.97) (xy 135.89 140.97)
		)
		(stroke
			(width 0)
			(type default)
		)
	)
	(wire
		(pts
			(xy 326.39 125.73) (xy 326.39 123.19)
		)
		(stroke
			(width 0)
			(type default)
		)
	)
	(wire
		(pts
			(xy 267.97 107.95) (xy 270.51 107.95)
		)
		(stroke
			(width 0)
			(type default)
		)
	)
	(wire
		(pts
			(xy 21.59 170.18) (xy 21.59 172.72)
		)
		(stroke
			(width 0)
			(type default)
		)
	)
	(wire
		(pts
			(xy 207.01 95.25) (xy 125.73 95.25)
		)
		(stroke
			(width 0)
			(type default)
		)
	)
	(wire
		(pts
			(xy 335.28 66.04) (xy 326.39 66.04)
		)
		(stroke
			(width 0)
			(type default)
		)
	)
	(wire
		(pts
			(xy 317.5 105.41) (xy 326.39 105.41)
		)
		(stroke
			(width 0)
			(type default)
		)
	)
	(wire
		(pts
			(xy 88.9 172.72) (xy 97.79 172.72)
		)
		(stroke
			(width 0)
			(type default)
		)
	)
	(wire
		(pts
			(xy 54.61 207.01) (xy 54.61 209.55)
		)
		(stroke
			(width 0)
			(type default)
		)
	)
	(wire
		(pts
			(xy 217.17 120.65) (xy 176.53 120.65)
		)
		(stroke
			(width 0)
			(type default)
		)
	)
	(wire
		(pts
			(xy 308.61 123.19) (xy 317.5 123.19)
		)
		(stroke
			(width 0)
			(type default)
		)
	)
	(wire
		(pts
			(xy 214.63 97.79) (xy 214.63 95.25)
		)
		(stroke
			(width 0)
			(type default)
		)
	)
	(wire
		(pts
			(xy 361.95 113.03) (xy 361.95 115.57)
		)
		(stroke
			(width 0)
			(type default)
		)
	)
	(wire
		(pts
			(xy 146.05 135.89) (xy 133.35 135.89)
		)
		(stroke
			(width 0)
			(type default)
		)
	)
	(wire
		(pts
			(xy 379.73 66.04) (xy 388.62 66.04)
		)
		(stroke
			(width 0)
			(type default)
		)
	)
	(wire
		(pts
			(xy 299.72 130.81) (xy 299.72 133.35)
		)
		(stroke
			(width 0)
			(type default)
		)
	)
	(wire
		(pts
			(xy 379.73 125.73) (xy 379.73 123.19)
		)
		(stroke
			(width 0)
			(type default)
		)
	)
	(wire
		(pts
			(xy 41.91 172.72) (xy 31.75 172.72)
		)
		(stroke
			(width 0)
			(type default)
		)
	)
	(wire
		(pts
			(xy 41.91 100.33) (xy 41.91 102.87)
		)
		(stroke
			(width 0)
			(type default)
		)
	)
	(wire
		(pts
			(xy 270.51 105.41) (xy 267.97 105.41)
		)
		(stroke
			(width 0)
			(type default)
		)
	)
	(wire
		(pts
			(xy 344.17 107.95) (xy 344.17 105.41)
		)
		(stroke
			(width 0)
			(type default)
		)
	)
	(wire
		(pts
			(xy 97.79 73.66) (xy 97.79 76.2)
		)
		(stroke
			(width 0)
			(type default)
		)
	)
	(wire
		(pts
			(xy 361.95 52.07) (xy 361.95 54.61)
		)
		(stroke
			(width 0)
			(type default)
		)
	)
	(wire
		(pts
			(xy 135.89 140.97) (xy 135.89 252.73)
		)
		(stroke
			(width 0)
			(type default)
		)
	)
	(wire
		(pts
			(xy 299.72 123.19) (xy 299.72 125.73)
		)
		(stroke
			(width 0)
			(type default)
		)
	)
	(wire
		(pts
			(xy 115.57 119.38) (xy 124.46 119.38)
		)
		(stroke
			(width 0)
			(type default)
		)
	)
	(wire
		(pts
			(xy 146.05 135.89) (xy 217.17 135.89)
		)
		(stroke
			(width 0)
			(type default)
		)
	)
	(wire
		(pts
			(xy 283.21 142.24) (xy 289.56 142.24)
		)
		(stroke
			(width 0)
			(type default)
		)
	)
	(wire
		(pts
			(xy 267.97 118.11) (xy 273.05 118.11)
		)
		(stroke
			(width 0)
			(type default)
		)
	)
	(wire
		(pts
			(xy 71.12 153.67) (xy 71.12 156.21)
		)
		(stroke
			(width 0)
			(type default)
		)
	)
	(wire
		(pts
			(xy 353.06 52.07) (xy 353.06 54.61)
		)
		(stroke
			(width 0)
			(type default)
		)
	)
	(wire
		(pts
			(xy 41.91 92.71) (xy 45.72 92.71)
		)
		(stroke
			(width 0)
			(type default)
		)
	)
	(wire
		(pts
			(xy 54.61 199.39) (xy 54.61 201.93)
		)
		(stroke
			(width 0)
			(type default)
		)
	)
	(wire
		(pts
			(xy 344.17 73.66) (xy 344.17 76.2)
		)
		(stroke
			(width 0)
			(type default)
		)
	)
	(wire
		(pts
			(xy 326.39 46.99) (xy 326.39 44.45)
		)
		(stroke
			(width 0)
			(type default)
		)
	)
	(wire
		(pts
			(xy 31.75 148.59) (xy 31.75 146.05)
		)
		(stroke
			(width 0)
			(type default)
		)
	)
	(wire
		(pts
			(xy 299.72 83.82) (xy 308.61 83.82)
		)
		(stroke
			(width 0)
			(type default)
		)
	)
	(wire
		(pts
			(xy 344.17 52.07) (xy 344.17 54.61)
		)
		(stroke
			(width 0)
			(type default)
		)
	)
	(wire
		(pts
			(xy 292.1 142.24) (xy 300.99 142.24)
		)
		(stroke
			(width 0)
			(type default)
		)
	)
	(wire
		(pts
			(xy 270.51 107.95) (xy 270.51 105.41)
		)
		(stroke
			(width 0)
			(type default)
		)
	)
	(wire
		(pts
			(xy 267.97 143.51) (xy 270.51 143.51)
		)
		(stroke
			(width 0)
			(type default)
		)
	)
	(wire
		(pts
			(xy 39.37 233.68) (xy 39.37 236.22)
		)
		(stroke
			(width 0)
			(type default)
		)
	)
	(wire
		(pts
			(xy 326.39 73.66) (xy 326.39 76.2)
		)
		(stroke
			(width 0)
			(type default)
		)
	)
	(wire
		(pts
			(xy 308.61 91.44) (xy 308.61 93.98)
		)
		(stroke
			(width 0)
			(type default)
		)
	)
	(wire
		(pts
			(xy 146.05 78.74) (xy 146.05 135.89)
		)
		(stroke
			(width 0)
			(type default)
		)
	)
	(wire
		(pts
			(xy 33.02 44.45) (xy 44.45 44.45)
		)
		(stroke
			(width 0)
			(type default)
		)
	)
	(wire
		(pts
			(xy 214.63 90.17) (xy 217.17 90.17)
		)
		(stroke
			(width 0)
			(type default)
		)
	)
	(wire
		(pts
			(xy 97.79 121.92) (xy 97.79 119.38)
		)
		(stroke
			(width 0)
			(type default)
		)
	)
	(wire
		(pts
			(xy 115.57 226.06) (xy 133.35 226.06)
		)
		(stroke
			(width 0)
			(type default)
		)
	)
	(wire
		(pts
			(xy 125.73 66.04) (xy 125.73 95.25)
		)
		(stroke
			(width 0)
			(type default)
		)
	)
	(wire
		(pts
			(xy 270.51 90.17) (xy 267.97 90.17)
		)
		(stroke
			(width 0)
			(type default)
		)
	)
	(wire
		(pts
			(xy 53.34 180.34) (xy 53.34 182.88)
		)
		(stroke
			(width 0)
			(type default)
		)
	)
	(wire
		(pts
			(xy 21.59 250.19) (xy 21.59 252.73)
		)
		(stroke
			(width 0)
			(type default)
		)
	)
	(wire
		(pts
			(xy 379.73 123.19) (xy 388.62 123.19)
		)
		(stroke
			(width 0)
			(type default)
		)
	)
	(wire
		(pts
			(xy 106.68 119.38) (xy 115.57 119.38)
		)
		(stroke
			(width 0)
			(type default)
		)
	)
	(wire
		(pts
			(xy 335.28 44.45) (xy 344.17 44.45)
		)
		(stroke
			(width 0)
			(type default)
		)
	)
	(wire
		(pts
			(xy 41.91 146.05) (xy 45.72 146.05)
		)
		(stroke
			(width 0)
			(type default)
		)
	)
	(wire
		(pts
			(xy 53.34 146.05) (xy 53.34 148.59)
		)
		(stroke
			(width 0)
			(type default)
		)
	)
	(wire
		(pts
			(xy 97.79 46.99) (xy 97.79 44.45)
		)
		(stroke
			(width 0)
			(type default)
		)
	)
	(wire
		(pts
			(xy 115.57 180.34) (xy 115.57 182.88)
		)
		(stroke
			(width 0)
			(type default)
		)
	)
	(wire
		(pts
			(xy 106.68 148.59) (xy 106.68 146.05)
		)
		(stroke
			(width 0)
			(type default)
		)
	)
	(wire
		(pts
			(xy 300.99 152.4) (xy 300.99 149.86)
		)
		(stroke
			(width 0)
			(type default)
		)
	)
	(wire
		(pts
			(xy 21.59 116.84) (xy 21.59 119.38)
		)
		(stroke
			(width 0)
			(type default)
		)
	)
	(wire
		(pts
			(xy 361.95 105.41) (xy 370.84 105.41)
		)
		(stroke
			(width 0)
			(type default)
		)
	)
	(wire
		(pts
			(xy 283.21 105.41) (xy 293.37 105.41)
		)
		(stroke
			(width 0)
			(type default)
		)
	)
	(wire
		(pts
			(xy 267.97 95.25) (xy 270.51 95.25)
		)
		(stroke
			(width 0)
			(type default)
		)
	)
	(wire
		(pts
			(xy 135.89 252.73) (xy 66.04 252.73)
		)
		(stroke
			(width 0)
			(type default)
		)
	)
	(wire
		(pts
			(xy 62.23 66.04) (xy 88.9 66.04)
		)
		(stroke
			(width 0)
			(type default)
		)
	)
	(wire
		(pts
			(xy 53.34 119.38) (xy 53.34 121.92)
		)
		(stroke
			(width 0)
			(type default)
		)
	)
	(wire
		(pts
			(xy 379.73 86.36) (xy 379.73 83.82)
		)
		(stroke
			(width 0)
			(type default)
		)
	)
	(wire
		(pts
			(xy 106.68 172.72) (xy 97.79 172.72)
		)
		(stroke
			(width 0)
			(type default)
		)
	)
	(wire
		(pts
			(xy 53.34 100.33) (xy 53.34 102.87)
		)
		(stroke
			(width 0)
			(type default)
		)
	)
	(wire
		(pts
			(xy 326.39 113.03) (xy 326.39 115.57)
		)
		(stroke
			(width 0)
			(type default)
		)
	)
	(wire
		(pts
			(xy 49.53 199.39) (xy 54.61 199.39)
		)
		(stroke
			(width 0)
			(type default)
		)
	)
	(wire
		(pts
			(xy 49.53 226.06) (xy 54.61 226.06)
		)
		(stroke
			(width 0)
			(type default)
		)
	)
	(wire
		(pts
			(xy 50.8 119.38) (xy 53.34 119.38)
		)
		(stroke
			(width 0)
			(type default)
		)
	)
	(wire
		(pts
			(xy 344.17 113.03) (xy 344.17 115.57)
		)
		(stroke
			(width 0)
			(type default)
		)
	)
	(wire
		(pts
			(xy 41.91 153.67) (xy 41.91 156.21)
		)
		(stroke
			(width 0)
			(type default)
		)
	)
	(wire
		(pts
			(xy 335.28 107.95) (xy 335.28 105.41)
		)
		(stroke
			(width 0)
			(type default)
		)
	)
	(wire
		(pts
			(xy 106.68 46.99) (xy 106.68 44.45)
		)
		(stroke
			(width 0)
			(type default)
		)
	)
	(wire
		(pts
			(xy 300.99 142.24) (xy 309.88 142.24)
		)
		(stroke
			(width 0)
			(type default)
		)
	)
	(wire
		(pts
			(xy 370.84 52.07) (xy 370.84 54.61)
		)
		(stroke
			(width 0)
			(type default)
		)
	)
	(wire
		(pts
			(xy 53.34 44.45) (xy 62.23 44.45)
		)
		(stroke
			(width 0)
			(type default)
		)
	)
	(wire
		(pts
			(xy 49.53 252.73) (xy 54.61 252.73)
		)
		(stroke
			(width 0)
			(type default)
		)
	)
	(wire
		(pts
			(xy 135.89 140.97) (xy 135.89 78.74)
		)
		(stroke
			(width 0)
			(type default)
		)
	)
	(wire
		(pts
			(xy 214.63 110.49) (xy 217.17 110.49)
		)
		(stroke
			(width 0)
			(type default)
		)
	)
	(wire
		(pts
			(xy 53.34 127) (xy 53.34 129.54)
		)
		(stroke
			(width 0)
			(type default)
		)
	)
	(wire
		(pts
			(xy 270.51 143.51) (xy 270.51 152.4)
		)
		(stroke
			(width 0)
			(type default)
		)
	)
	(wire
		(pts
			(xy 115.57 228.6) (xy 115.57 226.06)
		)
		(stroke
			(width 0)
			(type default)
		)
	)
	(wire
		(pts
			(xy 397.51 52.07) (xy 397.51 54.61)
		)
		(stroke
			(width 0)
			(type default)
		)
	)
	(wire
		(pts
			(xy 62.23 44.45) (xy 80.01 44.45)
		)
		(stroke
			(width 0)
			(type default)
		)
	)
	(wire
		(pts
			(xy 66.04 144.78) (xy 66.04 146.05)
		)
		(stroke
			(width 0)
			(type default)
		)
	)
	(wire
		(pts
			(xy 106.68 66.04) (xy 115.57 66.04)
		)
		(stroke
			(width 0)
			(type default)
		)
	)
	(wire
		(pts
			(xy 397.51 91.44) (xy 397.51 93.98)
		)
		(stroke
			(width 0)
			(type default)
		)
	)
	(wire
		(pts
			(xy 317.5 66.04) (xy 326.39 66.04)
		)
		(stroke
			(width 0)
			(type default)
		)
	)
	(wire
		(pts
			(xy 353.06 113.03) (xy 353.06 115.57)
		)
		(stroke
			(width 0)
			(type default)
		)
	)
	(wire
		(pts
			(xy 353.06 83.82) (xy 361.95 83.82)
		)
		(stroke
			(width 0)
			(type default)
		)
	)
	(wire
		(pts
			(xy 106.68 180.34) (xy 106.68 182.88)
		)
		(stroke
			(width 0)
			(type default)
		)
	)
	(wire
		(pts
			(xy 267.97 133.35) (xy 270.51 133.35)
		)
		(stroke
			(width 0)
			(type default)
		)
	)
	(wire
		(pts
			(xy 299.72 52.07) (xy 299.72 54.61)
		)
		(stroke
			(width 0)
			(type default)
		)
	)
	(wire
		(pts
			(xy 267.97 97.79) (xy 270.51 97.79)
		)
		(stroke
			(width 0)
			(type default)
		)
	)
	(wire
		(pts
			(xy 335.28 73.66) (xy 335.28 76.2)
		)
		(stroke
			(width 0)
			(type default)
		)
	)
	(wire
		(pts
			(xy 50.8 92.71) (xy 53.34 92.71)
		)
		(stroke
			(width 0)
			(type default)
		)
	)
	(wire
		(pts
			(xy 62.23 153.67) (xy 62.23 156.21)
		)
		(stroke
			(width 0)
			(type default)
		)
	)
	(wire
		(pts
			(xy 317.5 125.73) (xy 317.5 123.19)
		)
		(stroke
			(width 0)
			(type default)
		)
	)
	(wire
		(pts
			(xy 166.37 125.73) (xy 128.27 125.73)
		)
		(stroke
			(width 0)
			(type default)
		)
	)
	(wire
		(pts
			(xy 97.79 207.01) (xy 97.79 209.55)
		)
		(stroke
			(width 0)
			(type default)
		)
	)
	(wire
		(pts
			(xy 62.23 66.04) (xy 53.34 66.04)
		)
		(stroke
			(width 0)
			(type default)
		)
	)
	(wire
		(pts
			(xy 388.62 44.45) (xy 397.51 44.45)
		)
		(stroke
			(width 0)
			(type default)
		)
	)
	(wire
		(pts
			(xy 317.5 113.03) (xy 317.5 115.57)
		)
		(stroke
			(width 0)
			(type default)
		)
	)
	(wire
		(pts
			(xy 317.5 68.58) (xy 317.5 66.04)
		)
		(stroke
			(width 0)
			(type default)
		)
	)
	(wire
		(pts
			(xy 370.84 130.81) (xy 370.84 133.35)
		)
		(stroke
			(width 0)
			(type default)
		)
	)
	(wire
		(pts
			(xy 293.37 105.41) (xy 299.72 105.41)
		)
		(stroke
			(width 0)
			(type default)
		)
	)
	(wire
		(pts
			(xy 53.34 46.99) (xy 53.34 44.45)
		)
		(stroke
			(width 0)
			(type default)
		)
	)
	(wire
		(pts
			(xy 361.95 125.73) (xy 361.95 123.19)
		)
		(stroke
			(width 0)
			(type default)
		)
	)
	(wire
		(pts
			(xy 53.34 172.72) (xy 53.34 175.26)
		)
		(stroke
			(width 0)
			(type default)
		)
	)
	(wire
		(pts
			(xy 326.39 107.95) (xy 326.39 105.41)
		)
		(stroke
			(width 0)
			(type default)
		)
	)
	(wire
		(pts
			(xy 53.34 66.04) (xy 53.34 68.58)
		)
		(stroke
			(width 0)
			(type default)
		)
	)
	(wire
		(pts
			(xy 293.37 123.19) (xy 293.37 105.41)
		)
		(stroke
			(width 0)
			(type default)
		)
	)
	(wire
		(pts
			(xy 289.56 139.7) (xy 289.56 142.24)
		)
		(stroke
			(width 0)
			(type default)
		)
	)
	(wire
		(pts
			(xy 317.5 66.04) (xy 308.61 66.04)
		)
		(stroke
			(width 0)
			(type default)
		)
	)
	(wire
		(pts
			(xy 283.21 118.11) (xy 283.21 142.24)
		)
		(stroke
			(width 0)
			(type default)
		)
	)
	(wire
		(pts
			(xy 124.46 119.38) (xy 124.46 110.49)
		)
		(stroke
			(width 0)
			(type default)
		)
	)
	(wire
		(pts
			(xy 44.45 52.07) (xy 44.45 54.61)
		)
		(stroke
			(width 0)
			(type default)
		)
	)
	(wire
		(pts
			(xy 214.63 78.74) (xy 214.63 90.17)
		)
		(stroke
			(width 0)
			(type default)
		)
	)
	(wire
		(pts
			(xy 353.06 86.36) (xy 353.06 83.82)
		)
		(stroke
			(width 0)
			(type default)
		)
	)
	(wire
		(pts
			(xy 379.73 73.66) (xy 379.73 76.2)
		)
		(stroke
			(width 0)
			(type default)
		)
	)
	(wire
		(pts
			(xy 88.9 121.92) (xy 88.9 119.38)
		)
		(stroke
			(width 0)
			(type default)
		)
	)
	(wire
		(pts
			(xy 317.5 107.95) (xy 317.5 105.41)
		)
		(stroke
			(width 0)
			(type default)
		)
	)
	(wire
		(pts
			(xy 308.61 83.82) (xy 317.5 83.82)
		)
		(stroke
			(width 0)
			(type default)
		)
	)
	(wire
		(pts
			(xy 106.68 119.38) (xy 106.68 121.92)
		)
		(stroke
			(width 0)
			(type default)
		)
	)
	(wire
		(pts
			(xy 21.59 153.67) (xy 21.59 156.21)
		)
		(stroke
			(width 0)
			(type default)
		)
	)
	(wire
		(pts
			(xy 270.51 140.97) (xy 270.51 143.51)
		)
		(stroke
			(width 0)
			(type default)
		)
	)
	(wire
		(pts
			(xy 397.51 68.58) (xy 397.51 66.04)
		)
		(stroke
			(width 0)
			(type default)
		)
	)
	(wire
		(pts
			(xy 299.72 123.19) (xy 308.61 123.19)
		)
		(stroke
			(width 0)
			(type default)
		)
	)
	(wire
		(pts
			(xy 299.72 105.41) (xy 299.72 107.95)
		)
		(stroke
			(width 0)
			(type default)
		)
	)
	(wire
		(pts
			(xy 88.9 175.26) (xy 88.9 172.72)
		)
		(stroke
			(width 0)
			(type default)
		)
	)
	(wire
		(pts
			(xy 353.06 105.41) (xy 361.95 105.41)
		)
		(stroke
			(width 0)
			(type default)
		)
	)
	(wire
		(pts
			(xy 214.63 95.25) (xy 217.17 95.25)
		)
		(stroke
			(width 0)
			(type default)
		)
	)
	(wire
		(pts
			(xy 388.62 130.81) (xy 388.62 133.35)
		)
		(stroke
			(width 0)
			(type default)
		)
	)
	(wire
		(pts
			(xy 39.37 252.73) (xy 39.37 255.27)
		)
		(stroke
			(width 0)
			(type default)
		)
	)
	(wire
		(pts
			(xy 39.37 260.35) (xy 39.37 262.89)
		)
		(stroke
			(width 0)
			(type default)
		)
	)
	(wire
		(pts
			(xy 31.75 146.05) (xy 41.91 146.05)
		)
		(stroke
			(width 0)
			(type default)
		)
	)
	(wire
		(pts
			(xy 115.57 146.05) (xy 106.68 146.05)
		)
		(stroke
			(width 0)
			(type default)
		)
	)
	(wire
		(pts
			(xy 88.9 46.99) (xy 88.9 44.45)
		)
		(stroke
			(width 0)
			(type default)
		)
	)
	(wire
		(pts
			(xy 53.34 146.05) (xy 62.23 146.05)
		)
		(stroke
			(width 0)
			(type default)
		)
	)
	(wire
		(pts
			(xy 308.61 52.07) (xy 308.61 54.61)
		)
		(stroke
			(width 0)
			(type default)
		)
	)
	(wire
		(pts
			(xy 50.8 146.05) (xy 53.34 146.05)
		)
		(stroke
			(width 0)
			(type default)
		)
	)
	(wire
		(pts
			(xy 270.51 115.57) (xy 270.51 110.49)
		)
		(stroke
			(width 0)
			(type default)
		)
	)
	(wire
		(pts
			(xy 317.5 46.99) (xy 317.5 44.45)
		)
		(stroke
			(width 0)
			(type default)
		)
	)
	(wire
		(pts
			(xy 39.37 199.39) (xy 39.37 201.93)
		)
		(stroke
			(width 0)
			(type default)
		)
	)
	(wire
		(pts
			(xy 53.34 92.71) (xy 67.31 92.71)
		)
		(stroke
			(width 0)
			(type default)
		)
	)
	(wire
		(pts
			(xy 397.51 44.45) (xy 397.51 46.99)
		)
		(stroke
			(width 0)
			(type default)
		)
	)
	(wire
		(pts
			(xy 283.21 144.78) (xy 283.21 142.24)
		)
		(stroke
			(width 0)
			(type default)
		)
	)
	(wire
		(pts
			(xy 326.39 130.81) (xy 326.39 133.35)
		)
		(stroke
			(width 0)
			(type default)
		)
	)
	(wire
		(pts
			(xy 88.9 44.45) (xy 97.79 44.45)
		)
		(stroke
			(width 0)
			(type default)
		)
	)
	(wire
		(pts
			(xy 97.79 146.05) (xy 106.68 146.05)
		)
		(stroke
			(width 0)
			(type default)
		)
	)
	(wire
		(pts
			(xy 344.17 130.81) (xy 344.17 133.35)
		)
		(stroke
			(width 0)
			(type default)
		)
	)
	(wire
		(pts
			(xy 97.79 127) (xy 97.79 129.54)
		)
		(stroke
			(width 0)
			(type default)
		)
	)
	(wire
		(pts
			(xy 41.91 146.05) (xy 41.91 148.59)
		)
		(stroke
			(width 0)
			(type default)
		)
	)
	(wire
		(pts
			(xy 388.62 46.99) (xy 388.62 44.45)
		)
		(stroke
			(width 0)
			(type default)
		)
	)
	(wire
		(pts
			(xy 326.39 91.44) (xy 326.39 93.98)
		)
		(stroke
			(width 0)
			(type default)
		)
	)
	(wire
		(pts
			(xy 106.68 127) (xy 106.68 129.54)
		)
		(stroke
			(width 0)
			(type default)
		)
	)
	(wire
		(pts
			(xy 67.31 105.41) (xy 196.85 105.41)
		)
		(stroke
			(width 0)
			(type default)
		)
	)
	(wire
		(pts
			(xy 353.06 125.73) (xy 353.06 123.19)
		)
		(stroke
			(width 0)
			(type default)
		)
	)
	(wire
		(pts
			(xy 41.91 180.34) (xy 41.91 182.88)
		)
		(stroke
			(width 0)
			(type default)
		)
	)
	(wire
		(pts
			(xy 88.9 153.67) (xy 88.9 156.21)
		)
		(stroke
			(width 0)
			(type default)
		)
	)
	(wire
		(pts
			(xy 379.73 83.82) (xy 388.62 83.82)
		)
		(stroke
			(width 0)
			(type default)
		)
	)
	(wire
		(pts
			(xy 39.37 199.39) (xy 44.45 199.39)
		)
		(stroke
			(width 0)
			(type default)
		)
	)
	(wire
		(pts
			(xy 125.73 120.65) (xy 176.53 120.65)
		)
		(stroke
			(width 0)
			(type default)
		)
	)
	(wire
		(pts
			(xy 115.57 153.67) (xy 115.57 156.21)
		)
		(stroke
			(width 0)
			(type default)
		)
	)
	(wire
		(pts
			(xy 293.37 83.82) (xy 299.72 83.82)
		)
		(stroke
			(width 0)
			(type default)
		)
	)
	(wire
		(pts
			(xy 299.72 113.03) (xy 299.72 115.57)
		)
		(stroke
			(width 0)
			(type default)
		)
	)
	(wire
		(pts
			(xy 293.37 95.25) (xy 293.37 83.82)
		)
		(stroke
			(width 0)
			(type default)
		)
	)
	(wire
		(pts
			(xy 361.95 86.36) (xy 361.95 83.82)
		)
		(stroke
			(width 0)
			(type default)
		)
	)
	(wire
		(pts
			(xy 88.9 148.59) (xy 88.9 146.05)
		)
		(stroke
			(width 0)
			(type default)
		)
	)
	(wire
		(pts
			(xy 115.57 199.39) (xy 115.57 201.93)
		)
		(stroke
			(width 0)
			(type default)
		)
	)
	(wire
		(pts
			(xy 370.84 68.58) (xy 370.84 66.04)
		)
		(stroke
			(width 0)
			(type default)
		)
	)
	(wire
		(pts
			(xy 234.95 179.07) (xy 238.76 179.07)
		)
		(stroke
			(width 0)
			(type default)
		)
	)
	(wire
		(pts
			(xy 62.23 146.05) (xy 62.23 148.59)
		)
		(stroke
			(width 0)
			(type default)
		)
	)
	(wire
		(pts
			(xy 299.72 123.19) (xy 293.37 123.19)
		)
		(stroke
			(width 0)
			(type default)
		)
	)
	(wire
		(pts
			(xy 361.95 68.58) (xy 361.95 66.04)
		)
		(stroke
			(width 0)
			(type default)
		)
	)
	(wire
		(pts
			(xy 361.95 91.44) (xy 361.95 93.98)
		)
		(stroke
			(width 0)
			(type default)
		)
	)
	(wire
		(pts
			(xy 214.63 97.79) (xy 217.17 97.79)
		)
		(stroke
			(width 0)
			(type default)
		)
	)
	(wire
		(pts
			(xy 166.37 78.74) (xy 166.37 125.73)
		)
		(stroke
			(width 0)
			(type default)
		)
	)
	(wire
		(pts
			(xy 335.28 46.99) (xy 335.28 44.45)
		)
		(stroke
			(width 0)
			(type default)
		)
	)
	(wire
		(pts
			(xy 115.57 146.05) (xy 115.57 148.59)
		)
		(stroke
			(width 0)
			(type default)
		)
	)
	(wire
		(pts
			(xy 283.21 115.57) (xy 283.21 118.11)
		)
		(stroke
			(width 0)
			(type default)
		)
	)
	(wire
		(pts
			(xy 370.84 91.44) (xy 370.84 93.98)
		)
		(stroke
			(width 0)
			(type default)
		)
	)
	(wire
		(pts
			(xy 388.62 68.58) (xy 388.62 66.04)
		)
		(stroke
			(width 0)
			(type default)
		)
	)
	(wire
		(pts
			(xy 353.06 130.81) (xy 353.06 133.35)
		)
		(stroke
			(width 0)
			(type default)
		)
	)
	(wire
		(pts
			(xy 196.85 78.74) (xy 196.85 105.41)
		)
		(stroke
			(width 0)
			(type default)
		)
	)
	(wire
		(pts
			(xy 335.28 113.03) (xy 335.28 115.57)
		)
		(stroke
			(width 0)
			(type default)
		)
	)
	(wire
		(pts
			(xy 283.21 78.74) (xy 283.21 105.41)
		)
		(stroke
			(width 0)
			(type default)
		)
	)
	(wire
		(pts
			(xy 217.17 100.33) (xy 214.63 100.33)
		)
		(stroke
			(width 0)
			(type default)
		)
	)
	(wire
		(pts
			(xy 66.04 146.05) (xy 71.12 146.05)
		)
		(stroke
			(width 0)
			(type default)
		)
	)
	(wire
		(pts
			(xy 71.12 180.34) (xy 71.12 182.88)
		)
		(stroke
			(width 0)
			(type default)
		)
	)
	(wire
		(pts
			(xy 97.79 199.39) (xy 88.9 199.39)
		)
		(stroke
			(width 0)
			(type default)
		)
	)
	(wire
		(pts
			(xy 370.84 73.66) (xy 370.84 76.2)
		)
		(stroke
			(width 0)
			(type default)
		)
	)
	(wire
		(pts
			(xy 88.9 119.38) (xy 97.79 119.38)
		)
		(stroke
			(width 0)
			(type default)
		)
	)
	(wire
		(pts
			(xy 41.91 92.71) (xy 41.91 95.25)
		)
		(stroke
			(width 0)
			(type default)
		)
	)
	(wire
		(pts
			(xy 267.97 135.89) (xy 270.51 135.89)
		)
		(stroke
			(width 0)
			(type default)
		)
	)
	(wire
		(pts
			(xy 335.28 91.44) (xy 335.28 93.98)
		)
		(stroke
			(width 0)
			(type default)
		)
	)
	(wire
		(pts
			(xy 66.04 172.72) (xy 71.12 172.72)
		)
		(stroke
			(width 0)
			(type default)
		)
	)
	(wire
		(pts
			(xy 71.12 175.26) (xy 71.12 172.72)
		)
		(stroke
			(width 0)
			(type default)
		)
	)
	(wire
		(pts
			(xy 344.17 123.19) (xy 353.06 123.19)
		)
		(stroke
			(width 0)
			(type default)
		)
	)
	(wire
		(pts
			(xy 62.23 172.72) (xy 53.34 172.72)
		)
		(stroke
			(width 0)
			(type default)
		)
	)
	(wire
		(pts
			(xy 21.59 90.17) (xy 21.59 92.71)
		)
		(stroke
			(width 0)
			(type default)
		)
	)
	(wire
		(pts
			(xy 326.39 123.19) (xy 344.17 123.19)
		)
		(stroke
			(width 0)
			(type default)
		)
	)
	(wire
		(pts
			(xy 217.17 130.81) (xy 156.21 130.81)
		)
		(stroke
			(width 0)
			(type default)
		)
	)
	(wire
		(pts
			(xy 41.91 172.72) (xy 41.91 175.26)
		)
		(stroke
			(width 0)
			(type default)
		)
	)
	(wire
		(pts
			(xy 276.86 95.25) (xy 293.37 95.25)
		)
		(stroke
			(width 0)
			(type default)
		)
	)
	(wire
		(pts
			(xy 97.79 119.38) (xy 106.68 119.38)
		)
		(stroke
			(width 0)
			(type default)
		)
	)
	(wire
		(pts
			(xy 361.95 66.04) (xy 353.06 66.04)
		)
		(stroke
			(width 0)
			(type default)
		)
	)
	(wire
		(pts
			(xy 370.84 113.03) (xy 370.84 115.57)
		)
		(stroke
			(width 0)
			(type default)
		)
	)
	(wire
		(pts
			(xy 388.62 83.82) (xy 397.51 83.82)
		)
		(stroke
			(width 0)
			(type default)
		)
	)
	(wire
		(pts
			(xy 370.84 83.82) (xy 379.73 83.82)
		)
		(stroke
			(width 0)
			(type default)
		)
	)
	(wire
		(pts
			(xy 97.79 180.34) (xy 97.79 182.88)
		)
		(stroke
			(width 0)
			(type default)
		)
	)
	(wire
		(pts
			(xy 361.95 46.99) (xy 361.95 44.45)
		)
		(stroke
			(width 0)
			(type default)
		)
	)
	(wire
		(pts
			(xy 353.06 123.19) (xy 361.95 123.19)
		)
		(stroke
			(width 0)
			(type default)
		)
	)
	(wire
		(pts
			(xy 66.04 226.06) (xy 115.57 226.06)
		)
		(stroke
			(width 0)
			(type default)
		)
	)
	(wire
		(pts
			(xy 278.13 118.11) (xy 283.21 118.11)
		)
		(stroke
			(width 0)
			(type default)
		)
	)
	(wire
		(pts
			(xy 21.59 146.05) (xy 31.75 146.05)
		)
		(stroke
			(width 0)
			(type default)
		)
	)
	(wire
		(pts
			(xy 270.51 78.74) (xy 270.51 90.17)
		)
		(stroke
			(width 0)
			(type default)
		)
	)
	(wire
		(pts
			(xy 53.34 153.67) (xy 53.34 156.21)
		)
		(stroke
			(width 0)
			(type default)
		)
	)
	(wire
		(pts
			(xy 66.04 118.11) (xy 66.04 119.38)
		)
		(stroke
			(width 0)
			(type default)
		)
	)
	(wire
		(pts
			(xy 283.21 152.4) (xy 283.21 149.86)
		)
		(stroke
			(width 0)
			(type default)
		)
	)
	(wire
		(pts
			(xy 106.68 172.72) (xy 115.57 172.72)
		)
		(stroke
			(width 0)
			(type default)
		)
	)
	(wire
		(pts
			(xy 353.06 68.58) (xy 353.06 66.04)
		)
		(stroke
			(width 0)
			(type default)
		)
	)
	(wire
		(pts
			(xy 326.39 44.45) (xy 335.28 44.45)
		)
		(stroke
			(width 0)
			(type default)
		)
	)
	(wire
		(pts
			(xy 88.9 127) (xy 88.9 129.54)
		)
		(stroke
			(width 0)
			(type default)
		)
	)
	(wire
		(pts
			(xy 353.06 73.66) (xy 353.06 76.2)
		)
		(stroke
			(width 0)
			(type default)
		)
	)
	(wire
		(pts
			(xy 290.83 44.45) (xy 290.83 90.17)
		)
		(stroke
			(width 0)
			(type default)
		)
	)
	(wire
		(pts
			(xy 88.9 66.04) (xy 97.79 66.04)
		)
		(stroke
			(width 0)
			(type default)
		)
	)
	(wire
		(pts
			(xy 317.5 73.66) (xy 317.5 76.2)
		)
		(stroke
			(width 0)
			(type default)
		)
	)
	(wire
		(pts
			(xy 397.51 73.66) (xy 397.51 76.2)
		)
		(stroke
			(width 0)
			(type default)
		)
	)
	(wire
		(pts
			(xy 115.57 66.04) (xy 125.73 66.04)
		)
		(stroke
			(width 0)
			(type default)
		)
	)
	(wire
		(pts
			(xy 267.97 115.57) (xy 270.51 115.57)
		)
		(stroke
			(width 0)
			(type default)
		)
	)
	(wire
		(pts
			(xy 270.51 130.81) (xy 270.51 133.35)
		)
		(stroke
			(width 0)
			(type default)
		)
	)
	(wire
		(pts
			(xy 335.28 86.36) (xy 335.28 83.82)
		)
		(stroke
			(width 0)
			(type default)
		)
	)
	(wire
		(pts
			(xy 88.9 207.01) (xy 88.9 209.55)
		)
		(stroke
			(width 0)
			(type default)
		)
	)
	(wire
		(pts
			(xy 344.17 66.04) (xy 353.06 66.04)
		)
		(stroke
			(width 0)
			(type default)
		)
	)
	(wire
		(pts
			(xy 397.51 86.36) (xy 397.51 83.82)
		)
		(stroke
			(width 0)
			(type default)
		)
	)
	(wire
		(pts
			(xy 214.63 110.49) (xy 214.63 113.03)
		)
		(stroke
			(width 0)
			(type default)
		)
	)
	(wire
		(pts
			(xy 299.72 46.99) (xy 299.72 44.45)
		)
		(stroke
			(width 0)
			(type default)
		)
	)
	(wire
		(pts
			(xy 31.75 172.72) (xy 21.59 172.72)
		)
		(stroke
			(width 0)
			(type default)
		)
	)
	(wire
		(pts
			(xy 217.17 115.57) (xy 214.63 115.57)
		)
		(stroke
			(width 0)
			(type default)
		)
	)
	(wire
		(pts
			(xy 361.95 66.04) (xy 370.84 66.04)
		)
		(stroke
			(width 0)
			(type default)
		)
	)
	(wire
		(pts
			(xy 299.72 86.36) (xy 299.72 83.82)
		)
		(stroke
			(width 0)
			(type default)
		)
	)
	(wire
		(pts
			(xy 106.68 199.39) (xy 97.79 199.39)
		)
		(stroke
			(width 0)
			(type default)
		)
	)
	(wire
		(pts
			(xy 344.17 66.04) (xy 335.28 66.04)
		)
		(stroke
			(width 0)
			(type default)
		)
	)
	(wire
		(pts
			(xy 125.73 120.65) (xy 125.73 146.05)
		)
		(stroke
			(width 0)
			(type default)
		)
	)
	(wire
		(pts
			(xy 106.68 52.07) (xy 106.68 54.61)
		)
		(stroke
			(width 0)
			(type default)
		)
	)
	(wire
		(pts
			(xy 317.5 130.81) (xy 317.5 133.35)
		)
		(stroke
			(width 0)
			(type default)
		)
	)
	(wire
		(pts
			(xy 21.59 119.38) (xy 41.91 119.38)
		)
		(stroke
			(width 0)
			(type default)
		)
	)
	(wire
		(pts
			(xy 309.88 142.24) (xy 309.88 144.78)
		)
		(stroke
			(width 0)
			(type default)
		)
	)
	(wire
		(pts
			(xy 370.84 123.19) (xy 379.73 123.19)
		)
		(stroke
			(width 0)
			(type default)
		)
	)
	(wire
		(pts
			(xy 62.23 146.05) (xy 66.04 146.05)
		)
		(stroke
			(width 0)
			(type default)
		)
	)
	(wire
		(pts
			(xy 353.06 107.95) (xy 353.06 105.41)
		)
		(stroke
			(width 0)
			(type default)
		)
	)
	(wire
		(pts
			(xy 308.61 46.99) (xy 308.61 44.45)
		)
		(stroke
			(width 0)
			(type default)
		)
	)
	(wire
		(pts
			(xy 115.57 233.68) (xy 115.57 236.22)
		)
		(stroke
			(width 0)
			(type default)
		)
	)
	(wire
		(pts
			(xy 308.61 125.73) (xy 308.61 123.19)
		)
		(stroke
			(width 0)
			(type default)
		)
	)
	(wire
		(pts
			(xy 292.1 142.24) (xy 292.1 144.78)
		)
		(stroke
			(width 0)
			(type default)
		)
	)
	(wire
		(pts
			(xy 326.39 86.36) (xy 326.39 83.82)
		)
		(stroke
			(width 0)
			(type default)
		)
	)
	(wire
		(pts
			(xy 21.59 252.73) (xy 39.37 252.73)
		)
		(stroke
			(width 0)
			(type default)
		)
	)
	(wire
		(pts
			(xy 335.28 68.58) (xy 335.28 66.04)
		)
		(stroke
			(width 0)
			(type default)
		)
	)
	(wire
		(pts
			(xy 97.79 66.04) (xy 106.68 66.04)
		)
		(stroke
			(width 0)
			(type default)
		)
	)
	(wire
		(pts
			(xy 326.39 52.07) (xy 326.39 54.61)
		)
		(stroke
			(width 0)
			(type default)
		)
	)
	(wire
		(pts
			(xy 299.72 44.45) (xy 290.83 44.45)
		)
		(stroke
			(width 0)
			(type default)
		)
	)
	(wire
		(pts
			(xy 326.39 105.41) (xy 335.28 105.41)
		)
		(stroke
			(width 0)
			(type default)
		)
	)
	(wire
		(pts
			(xy 299.72 105.41) (xy 317.5 105.41)
		)
		(stroke
			(width 0)
			(type default)
		)
	)
	(wire
		(pts
			(xy 44.45 46.99) (xy 44.45 44.45)
		)
		(stroke
			(width 0)
			(type default)
		)
	)
	(wire
		(pts
			(xy 300.99 144.78) (xy 300.99 142.24)
		)
		(stroke
			(width 0)
			(type default)
		)
	)
	(wire
		(pts
			(xy 289.56 142.24) (xy 292.1 142.24)
		)
		(stroke
			(width 0)
			(type default)
		)
	)
	(wire
		(pts
			(xy 308.61 73.66) (xy 308.61 76.2)
		)
		(stroke
			(width 0)
			(type default)
		)
	)
	(wire
		(pts
			(xy 54.61 260.35) (xy 54.61 262.89)
		)
		(stroke
			(width 0)
			(type default)
		)
	)
	(wire
		(pts
			(xy 97.79 44.45) (xy 106.68 44.45)
		)
		(stroke
			(width 0)
			(type default)
		)
	)
	(wire
		(pts
			(xy 379.73 46.99) (xy 379.73 44.45)
		)
		(stroke
			(width 0)
			(type default)
		)
	)
	(wire
		(pts
			(xy 80.01 127) (xy 80.01 129.54)
		)
		(stroke
			(width 0)
			(type default)
		)
	)
	(wire
		(pts
			(xy 370.84 44.45) (xy 379.73 44.45)
		)
		(stroke
			(width 0)
			(type default)
		)
	)
	(wire
		(pts
			(xy 317.5 123.19) (xy 326.39 123.19)
		)
		(stroke
			(width 0)
			(type default)
		)
	)
	(wire
		(pts
			(xy 361.95 73.66) (xy 361.95 76.2)
		)
		(stroke
			(width 0)
			(type default)
		)
	)
	(wire
		(pts
			(xy 21.59 92.71) (xy 41.91 92.71)
		)
		(stroke
			(width 0)
			(type default)
		)
	)
	(wire
		(pts
			(xy 62.23 180.34) (xy 62.23 182.88)
		)
		(stroke
			(width 0)
			(type default)
		)
	)
	(wire
		(pts
			(xy 66.04 251.46) (xy 66.04 252.73)
		)
		(stroke
			(width 0)
			(type default)
		)
	)
	(wire
		(pts
			(xy 361.95 83.82) (xy 370.84 83.82)
		)
		(stroke
			(width 0)
			(type default)
		)
	)
	(wire
		(pts
			(xy 186.69 78.74) (xy 186.69 110.49)
		)
		(stroke
			(width 0)
			(type default)
		)
	)
	(wire
		(pts
			(xy 335.28 52.07) (xy 335.28 54.61)
		)
		(stroke
			(width 0)
			(type default)
		)
	)
	(wire
		(pts
			(xy 97.79 153.67) (xy 97.79 156.21)
		)
		(stroke
			(width 0)
			(type default)
		)
	)
	(wire
		(pts
			(xy 66.04 199.39) (xy 54.61 199.39)
		)
		(stroke
			(width 0)
			(type default)
		)
	)
	(wire
		(pts
			(xy 379.73 91.44) (xy 379.73 93.98)
		)
		(stroke
			(width 0)
			(type default)
		)
	)
	(wire
		(pts
			(xy 106.68 201.93) (xy 106.68 199.39)
		)
		(stroke
			(width 0)
			(type default)
		)
	)
	(wire
		(pts
			(xy 54.61 255.27) (xy 54.61 252.73)
		)
		(stroke
			(width 0)
			(type default)
		)
	)
	(wire
		(pts
			(xy 54.61 228.6) (xy 54.61 226.06)
		)
		(stroke
			(width 0)
			(type default)
		)
	)
	(wire
		(pts
			(xy 166.37 125.73) (xy 217.17 125.73)
		)
		(stroke
			(width 0)
			(type default)
		)
	)
	(wire
		(pts
			(xy 21.59 146.05) (xy 21.59 148.59)
		)
		(stroke
			(width 0)
			(type default)
		)
	)
	(wire
		(pts
			(xy 270.51 110.49) (xy 270.51 107.95)
		)
		(stroke
			(width 0)
			(type default)
		)
	)
	(wire
		(pts
			(xy 31.75 175.26) (xy 31.75 172.72)
		)
		(stroke
			(width 0)
			(type default)
		)
	)
	(wire
		(pts
			(xy 67.31 105.41) (xy 67.31 92.71)
		)
		(stroke
			(width 0)
			(type default)
		)
	)
	(wire
		(pts
			(xy 267.97 100.33) (xy 270.51 100.33)
		)
		(stroke
			(width 0)
			(type default)
		)
	)
	(wire
		(pts
			(xy 39.37 252.73) (xy 44.45 252.73)
		)
		(stroke
			(width 0)
			(type default)
		)
	)
	(wire
		(pts
			(xy 33.02 52.07) (xy 33.02 54.61)
		)
		(stroke
			(width 0)
			(type default)
		)
	)
	(wire
		(pts
			(xy 379.73 52.07) (xy 379.73 54.61)
		)
		(stroke
			(width 0)
			(type default)
		)
	)
	(wire
		(pts
			(xy 267.97 138.43) (xy 270.51 138.43)
		)
		(stroke
			(width 0)
			(type default)
		)
	)
	(wire
		(pts
			(xy 71.12 172.72) (xy 88.9 172.72)
		)
		(stroke
			(width 0)
			(type default)
		)
	)
	(wire
		(pts
			(xy 88.9 201.93) (xy 88.9 199.39)
		)
		(stroke
			(width 0)
			(type default)
		)
	)
	(wire
		(pts
			(xy 353.06 46.99) (xy 353.06 44.45)
		)
		(stroke
			(width 0)
			(type default)
		)
	)
	(wire
		(pts
			(xy 299.72 68.58) (xy 299.72 66.04)
		)
		(stroke
			(width 0)
			(type default)
		)
	)
	(wire
		(pts
			(xy 344.17 125.73) (xy 344.17 123.19)
		)
		(stroke
			(width 0)
			(type default)
		)
	)
	(wire
		(pts
			(xy 156.21 130.81) (xy 130.81 130.81)
		)
		(stroke
			(width 0)
			(type default)
		)
	)
	(wire
		(pts
			(xy 53.34 52.07) (xy 53.34 54.61)
		)
		(stroke
			(width 0)
			(type default)
		)
	)
	(wire
		(pts
			(xy 270.51 97.79) (xy 270.51 95.25)
		)
		(stroke
			(width 0)
			(type default)
		)
	)
	(wire
		(pts
			(xy 88.9 68.58) (xy 88.9 66.04)
		)
		(stroke
			(width 0)
			(type default)
		)
	)
	(wire
		(pts
			(xy 361.95 105.41) (xy 361.95 107.95)
		)
		(stroke
			(width 0)
			(type default)
		)
	)
	(wire
		(pts
			(xy 388.62 73.66) (xy 388.62 76.2)
		)
		(stroke
			(width 0)
			(type default)
		)
	)
	(wire
		(pts
			(xy 267.97 130.81) (xy 270.51 130.81)
		)
		(stroke
			(width 0)
			(type default)
		)
	)
	(wire
		(pts
			(xy 62.23 73.66) (xy 62.23 76.2)
		)
		(stroke
			(width 0)
			(type default)
		)
	)
	(wire
		(pts
			(xy 308.61 86.36) (xy 308.61 83.82)
		)
		(stroke
			(width 0)
			(type default)
		)
	)
	(wire
		(pts
			(xy 317.5 44.45) (xy 326.39 44.45)
		)
		(stroke
			(width 0)
			(type default)
		)
	)
	(wire
		(pts
			(xy 80.01 52.07) (xy 80.01 54.61)
		)
		(stroke
			(width 0)
			(type default)
		)
	)
	(wire
		(pts
			(xy 53.34 73.66) (xy 53.34 76.2)
		)
		(stroke
			(width 0)
			(type default)
		)
	)
	(wire
		(pts
			(xy 66.04 224.79) (xy 66.04 226.06)
		)
		(stroke
			(width 0)
			(type default)
		)
	)
	(wire
		(pts
			(xy 88.9 180.34) (xy 88.9 182.88)
		)
		(stroke
			(width 0)
			(type default)
		)
	)
	(wire
		(pts
			(xy 41.91 127) (xy 41.91 129.54)
		)
		(stroke
			(width 0)
			(type default)
		)
	)
	(wire
		(pts
			(xy 335.28 83.82) (xy 353.06 83.82)
		)
		(stroke
			(width 0)
			(type default)
		)
	)
	(wire
		(pts
			(xy 39.37 207.01) (xy 39.37 209.55)
		)
		(stroke
			(width 0)
			(type default)
		)
	)
	(wire
		(pts
			(xy 97.79 175.26) (xy 97.79 172.72)
		)
		(stroke
			(width 0)
			(type default)
		)
	)
	(wire
		(pts
			(xy 62.23 52.07) (xy 62.23 54.61)
		)
		(stroke
			(width 0)
			(type default)
		)
	)
	(wire
		(pts
			(xy 115.57 207.01) (xy 115.57 209.55)
		)
		(stroke
			(width 0)
			(type default)
		)
	)
	(wire
		(pts
			(xy 299.72 73.66) (xy 299.72 76.2)
		)
		(stroke
			(width 0)
			(type default)
		)
	)
	(wire
		(pts
			(xy 62.23 175.26) (xy 62.23 172.72)
		)
		(stroke
			(width 0)
			(type default)
		)
	)
	(wire
		(pts
			(xy 308.61 68.58) (xy 308.61 66.04)
		)
		(stroke
			(width 0)
			(type default)
		)
	)
	(wire
		(pts
			(xy 309.88 152.4) (xy 309.88 149.86)
		)
		(stroke
			(width 0)
			(type default)
		)
	)
	(wire
		(pts
			(xy 97.79 52.07) (xy 97.79 54.61)
		)
		(stroke
			(width 0)
			(type default)
		)
	)
	(wire
		(pts
			(xy 66.04 252.73) (xy 54.61 252.73)
		)
		(stroke
			(width 0)
			(type default)
		)
	)
	(wire
		(pts
			(xy 106.68 207.01) (xy 106.68 209.55)
		)
		(stroke
			(width 0)
			(type default)
		)
	)
	(wire
		(pts
			(xy 214.63 113.03) (xy 217.17 113.03)
		)
		(stroke
			(width 0)
			(type default)
		)
	)
	(wire
		(pts
			(xy 88.9 52.07) (xy 88.9 54.61)
		)
		(stroke
			(width 0)
			(type default)
		)
	)
	(wire
		(pts
			(xy 115.57 73.66) (xy 115.57 76.2)
		)
		(stroke
			(width 0)
			(type default)
		)
	)
	(wire
		(pts
			(xy 133.35 135.89) (xy 133.35 226.06)
		)
		(stroke
			(width 0)
			(type default)
		)
	)
	(wire
		(pts
			(xy 41.91 119.38) (xy 45.72 119.38)
		)
		(stroke
			(width 0)
			(type default)
		)
	)
	(wire
		(pts
			(xy 370.84 46.99) (xy 370.84 44.45)
		)
		(stroke
			(width 0)
			(type default)
		)
	)
	(wire
		(pts
			(xy 124.46 110.49) (xy 186.69 110.49)
		)
		(stroke
			(width 0)
			(type default)
		)
	)
	(wire
		(pts
			(xy 317.5 86.36) (xy 317.5 83.82)
		)
		(stroke
			(width 0)
			(type default)
		)
	)
	(rule_area
		(polyline
			(pts
				(xy 130.81 80.01) (xy 130.81 71.12) (xy 288.29 71.12) (xy 288.29 80.01)
			)
			(stroke
				(width 0)
				(type dash)
			)
			(fill
				(type none)
			)
		)
	)
	(netclass_flag ""
		(length 2.54)
		(shape round)
		(at 288.29 71.12 0)
		(fields_autoplaced yes)
		(effects
			(font
				(size 1.27 1.27)
			)
			(justify left bottom)
		)
		(property "Netclass" "PWR"
			(at 287.5915 68.58 0)
			(effects
				(font
					(size 1.27 1.27)
				)
				(justify right)
			)
		)
		(property "Component Class" ""
			(at 64.77 17.78 0)
			(effects
				(font
					(size 1.27 1.27)
					(italic yes)
				)
				(justify right)
			)
		)
	)
	(symbol
		(lib_id "antmicropower:GND")
		(at 39.37 236.22 0)
		(unit 1)
		(exclude_from_sim no)
		(in_bom yes)
		(on_board yes)
		(dnp no)
		(property "Reference" "#PWR0239"
			(at 48.26 238.76 0)
			(effects
				(font
					(size 1.27 1.27)
					(thickness 0.15)
				)
				(justify left bottom)
				(hide yes)
			)
		)
		(property "Value" "GND"
			(at 39.37 240.03 0)
			(effects
				(font
					(size 1.27 1.27)
					(thickness 0.15)
				)
			)
		)
		(property "Footprint" ""
			(at 48.26 243.84 0)
			(effects
				(font
					(size 1.27 1.27)
					(thickness 0.15)
				)
				(justify left bottom)
				(hide yes)
			)
		)
		(property "Datasheet" ""
			(at 48.26 248.92 0)
			(effects
				(font
					(size 1.27 1.27)
					(thickness 0.15)
				)
				(justify left bottom)
				(hide yes)
			)
		)
		(property "Description" ""
			(at 39.37 236.22 0)
			(effects
				(font
					(size 1.27 1.27)
				)
				(hide yes)
			)
		)
		(property "Author" "Antmicro"
			(at 48.26 243.84 0)
			(effects
				(font
					(size 1.27 1.27)
					(thickness 0.15)
				)
				(justify left bottom)
				(hide yes)
			)
		)
		(property "License" "Apache-2.0"
			(at 48.26 246.38 0)
			(effects
				(font
					(size 1.27 1.27)
					(thickness 0.15)
				)
				(justify left bottom)
				(hide yes)
			)
		)
		(pin "1"
		)
		(instances
			(project "OCuLink to 10GbE adapter"
				(path ""
					(reference "#PWR0239")
					(unit 1)
				)
			)
		)
	)
	(symbol
		(lib_id "antmicroFixedInductors:L_1u_10A_Bourns-SRP4021HMT")
		(at 273.05 118.11 0)
		(unit 1)
		(exclude_from_sim no)
		(in_bom yes)
		(on_board yes)
		(dnp no)
		(fields_autoplaced yes)
		(property "Reference" "L8"
			(at 275.59 113.03 0)
			(effects
				(font
					(size 1.27 1.27)
					(thickness 0.15)
				)
			)
		)
		(property "Value" "L_1u_10A_Bourns-SRP4021HMT"
			(at 288.29 128.27 0)
			(effects
				(font
					(size 1.27 1.27)
					(thickness 0.15)
				)
				(justify left bottom)
				(hide yes)
			)
		)
		(property "Footprint" "antmicro-footprints:L_Bourns-SRP4021HMT"
			(at 288.29 130.81 0)
			(effects
				(font
					(size 1.27 1.27)
					(thickness 0.15)
				)
				(justify left bottom)
				(hide yes)
			)
		)
		(property "Datasheet" "https://www.mouser.com/datasheet/2/54/Bourns_04_01_2025_SRP4021HMT_Datasheet-3580094.pdf"
			(at 288.29 133.35 0)
			(effects
				(font
					(size 1.27 1.27)
					(thickness 0.15)
				)
				(justify left bottom)
				(hide yes)
			)
		)
		(property "Description" "Power Inductors - SMD Ind,4.1x4.2x1.9mm,1uH+/-20%,10A, Shielded"
			(at 288.29 135.89 0)
			(effects
				(font
					(size 1.27 1.27)
					(thickness 0.15)
				)
				(justify left bottom)
				(hide yes)
			)
		)
		(property "Val" "1u/10A"
			(at 275.59 115.57 0)
			(effects
				(font
					(size 1.27 1.27)
					(thickness 0.15)
				)
			)
		)
		(property "Manufacturer" "Bourns"
			(at 288.29 138.43 0)
			(effects
				(font
					(size 1.27 1.27)
					(thickness 0.15)
				)
				(justify left bottom)
				(hide yes)
			)
		)
		(property "MPN" "SRP4021HMT-1R0M"
			(at 288.29 140.97 0)
			(effects
				(font
					(size 1.27 1.27)
					(thickness 0.15)
				)
				(justify left bottom)
				(hide yes)
			)
		)
		(property "ISat" ""
			(at 287.02 134.62 0)
			(effects
				(font
					(size 1.27 1.27)
				)
				(justify left)
				(hide yes)
			)
		)
		(property "Isat" "8A"
			(at 288.29 143.51 0)
			(effects
				(font
					(size 1.27 1.27)
					(thickness 0.15)
				)
				(justify left bottom)
				(hide yes)
			)
		)
		(property "IMax" ""
			(at 287.02 138.43 0)
			(effects
				(font
					(size 1.27 1.27)
					(thickness 0.15)
				)
				(justify left bottom)
				(hide yes)
			)
		)
		(property "Imax" "10A"
			(at 288.29 146.05 0)
			(effects
				(font
					(size 1.27 1.27)
					(thickness 0.15)
				)
				(justify left bottom)
				(hide yes)
			)
		)
		(property "Size" "4.2x4.1"
			(at 288.29 148.59 0)
			(effects
				(font
					(size 1.27 1.27)
					(thickness 0.15)
				)
				(justify left bottom)
				(hide yes)
			)
		)
		(property "Author" "Antmicro"
			(at 288.29 151.13 0)
			(effects
				(font
					(size 1.27 1.27)
					(thickness 0.15)
				)
				(justify left bottom)
				(hide yes)
			)
		)
		(property "License" "Apache-2.0"
			(at 288.29 153.67 0)
			(effects
				(font
					(size 1.27 1.27)
					(thickness 0.15)
				)
				(justify left bottom)
				(hide yes)
			)
		)
		(pin "1"
		)
		(pin "2"
		)
		(instances
			(project "OCuLink to 10GbE adapter"
				(path ""
					(reference "L8")
					(unit 1)
				)
			)
		)
	)
	(symbol
		(lib_id "antmicroFerriteBeadsandChips:FB_33Z_3A_Murata-BLM18PG_0603")
		(at 45.72 172.72 0)
		(unit 1)
		(exclude_from_sim no)
		(in_bom yes)
		(on_board yes)
		(dnp no)
		(fields_autoplaced yes)
		(property "Reference" "FB6"
			(at 48.2219 166.37 0)
			(effects
				(font
					(size 1.27 1.27)
					(thickness 0.15)
				)
			)
		)
		(property "Value" "FB_33Z_3A_Murata-BLM18PG_0603"
			(at 59.69 175.26 0)
			(effects
				(font
					(size 1.27 1.27)
					(thickness 0.15)
				)
				(justify left bottom)
				(hide yes)
			)
		)
		(property "Footprint" "antmicro-footprints:FB_0603_1608Metric"
			(at 59.69 180.34 0)
			(effects
				(font
					(size 1.27 1.27)
					(thickness 0.15)
				)
				(justify left bottom)
				(hide yes)
			)
		)
		(property "Datasheet" "https://www.murata.com/products/productdata/8796737273886/QNFA9101.pdf?1649080818000"
			(at 59.69 182.88 0)
			(effects
				(font
					(size 1.27 1.27)
					(thickness 0.15)
				)
				(justify left bottom)
				(hide yes)
			)
		)
		(property "Description" "Ferrite Bead, 0603 [1608 Metric], 33 ohm, 3 A, BLM18PG, 0.025 ohm, ± 25%, DC power line"
			(at 45.72 172.72 0)
			(effects
				(font
					(size 1.27 1.27)
				)
				(hide yes)
			)
		)
		(property "Val" "33Z/3A"
			(at 48.2219 168.91 0)
			(effects
				(font
					(size 1.27 1.27)
				)
			)
		)
		(property "MPN" "BLM18PG330SH1D"
			(at 59.69 185.42 0)
			(effects
				(font
					(size 1.27 1.27)
					(thickness 0.15)
				)
				(justify left bottom)
				(hide yes)
			)
		)
		(property "Manufacturer" "Murata"
			(at 59.69 187.96 0)
			(effects
				(font
					(size 1.27 1.27)
					(thickness 0.15)
				)
				(justify left bottom)
				(hide yes)
			)
		)
		(property "Current" ""
			(at 66.04 195.58 0)
			(effects
				(font
					(size 1.27 1.27)
					(thickness 0.15)
				)
				(justify left bottom)
				(hide yes)
			)
		)
		(property "Author" "Antmicro"
			(at 59.69 190.5 0)
			(effects
				(font
					(size 1.27 1.27)
					(thickness 0.15)
				)
				(justify left bottom)
				(hide yes)
			)
		)
		(property "License" "Apache-2.0"
			(at 59.69 193.04 0)
			(effects
				(font
					(size 1.27 1.27)
					(thickness 0.15)
				)
				(justify left bottom)
				(hide yes)
			)
		)
		(pin "2"
		)
		(pin "1"
		)
		(instances
			(project "OCuLink to 10GbE adapter"
				(path ""
					(reference "FB6")
					(unit 1)
				)
			)
		)
	)
	(symbol
		(lib_id "antmicropower:+1V8")
		(at 207.01 78.74 0)
		(unit 1)
		(exclude_from_sim no)
		(in_bom yes)
		(on_board yes)
		(dnp no)
		(property "Reference" "#PWR0158"
			(at 222.25 81.28 0)
			(effects
				(font
					(size 1.27 1.27)
					(thickness 0.15)
				)
				(justify left bottom)
				(hide yes)
			)
		)
		(property "Value" "+1V88"
			(at 207.01 74.93 0)
			(effects
				(font
					(size 1.27 1.27)
					(thickness 0.15)
				)
			)
		)
		(property "Footprint" ""
			(at 222.25 86.36 0)
			(effects
				(font
					(size 1.27 1.27)
					(thickness 0.15)
				)
				(justify left bottom)
				(hide yes)
			)
		)
		(property "Datasheet" ""
			(at 222.25 88.9 0)
			(effects
				(font
					(size 1.27 1.27)
					(thickness 0.15)
				)
				(justify left bottom)
				(hide yes)
			)
		)
		(property "Description" ""
			(at 207.01 78.74 0)
			(effects
				(font
					(size 1.27 1.27)
				)
				(hide yes)
			)
		)
		(property "Author" "Antmicro"
			(at 222.25 83.82 0)
			(effects
				(font
					(size 1.27 1.27)
					(thickness 0.15)
				)
				(justify left bottom)
				(hide yes)
			)
		)
		(property "License" "Apache-2.0"
			(at 222.25 86.36 0)
			(effects
				(font
					(size 1.27 1.27)
					(thickness 0.15)
				)
				(justify left bottom)
				(hide yes)
			)
		)
		(pin "1"
		)
		(instances
			(project "OCuLink to 10GbE adapter"
				(path ""
					(reference "#PWR0158")
					(unit 1)
				)
			)
		)
	)
	(symbol
		(lib_id "antmicropower:GND")
		(at 53.34 156.21 0)
		(unit 1)
		(exclude_from_sim no)
		(in_bom yes)
		(on_board yes)
		(dnp no)
		(property "Reference" "#PWR0214"
			(at 62.23 158.75 0)
			(effects
				(font
					(size 1.27 1.27)
					(thickness 0.15)
				)
				(justify left bottom)
				(hide yes)
			)
		)
		(property "Value" "GND"
			(at 53.34 160.02 0)
			(effects
				(font
					(size 1.27 1.27)
					(thickness 0.15)
				)
			)
		)
		(property "Footprint" ""
			(at 62.23 163.83 0)
			(effects
				(font
					(size 1.27 1.27)
					(thickness 0.15)
				)
				(justify left bottom)
				(hide yes)
			)
		)
		(property "Datasheet" ""
			(at 62.23 168.91 0)
			(effects
				(font
					(size 1.27 1.27)
					(thickness 0.15)
				)
				(justify left bottom)
				(hide yes)
			)
		)
		(property "Description" ""
			(at 53.34 156.21 0)
			(effects
				(font
					(size 1.27 1.27)
				)
				(hide yes)
			)
		)
		(property "Author" "Antmicro"
			(at 62.23 163.83 0)
			(effects
				(font
					(size 1.27 1.27)
					(thickness 0.15)
				)
				(justify left bottom)
				(hide yes)
			)
		)
		(property "License" "Apache-2.0"
			(at 62.23 166.37 0)
			(effects
				(font
					(size 1.27 1.27)
					(thickness 0.15)
				)
				(justify left bottom)
				(hide yes)
			)
		)
		(pin "1"
		)
		(instances
			(project "OCuLink to 10GbE adapter"
				(path ""
					(reference "#PWR0214")
					(unit 1)
				)
			)
		)
	)
	(symbol
		(lib_id "antmicroCapacitors0402:C_1u_25V_0402")
		(at 115.57 73.66 90)
		(unit 1)
		(exclude_from_sim no)
		(in_bom yes)
		(on_board yes)
		(dnp no)
		(property "Reference" "C104"
			(at 117.602 69.85 90)
			(effects
				(font
					(size 1.27 1.27)
					(thickness 0.15)
				)
				(justify right)
			)
		)
		(property "Value" "C_1u_25V_0402"
			(at 125.73 53.34 0)
			(effects
				(font
					(size 1.27 1.27)
					(thickness 0.15)
				)
				(justify left bottom)
				(hide yes)
			)
		)
		(property "Footprint" "antmicro-footprints:C_0402_1005Metric"
			(at 128.27 53.34 0)
			(effects
				(font
					(size 1.27 1.27)
					(thickness 0.15)
				)
				(justify left bottom)
				(hide yes)
			)
		)
		(property "Datasheet" "https://www.murata.com/products/productdetail?partno=GRM155R61E105KE11%23"
			(at 130.81 53.34 0)
			(effects
				(font
					(size 1.27 1.27)
					(thickness 0.15)
				)
				(justify left bottom)
				(hide yes)
			)
		)
		(property "Description" "SMD Multilayer Ceramic Capacitor, 1 µF, 25 V, 0402 [1005 Metric], ± 10%, X5R, GRM Series"
			(at 115.57 73.66 0)
			(effects
				(font
					(size 1.27 1.27)
				)
				(hide yes)
			)
		)
		(property "MPN" "GRM155R61E105KE11J"
			(at 133.35 53.34 0)
			(effects
				(font
					(size 1.27 1.27)
					(thickness 0.15)
				)
				(justify left bottom)
				(hide yes)
			)
		)
		(property "Manufacturer" "Murata"
			(at 135.89 53.34 0)
			(effects
				(font
					(size 1.27 1.27)
					(thickness 0.15)
				)
				(justify left bottom)
				(hide yes)
			)
		)
		(property "License" "Apache-2.0"
			(at 138.43 53.34 0)
			(effects
				(font
					(size 1.27 1.27)
					(thickness 0.15)
				)
				(justify left bottom)
				(hide yes)
			)
		)
		(property "Author" "Antmicro"
			(at 140.97 53.34 0)
			(effects
				(font
					(size 1.27 1.27)
					(thickness 0.15)
				)
				(justify left bottom)
				(hide yes)
			)
		)
		(property "Val" "1u"
			(at 117.602 72.39 90)
			(effects
				(font
					(size 1.27 1.27)
					(thickness 0.15)
				)
				(justify right)
			)
		)
		(property "Voltage" "25V"
			(at 143.51 53.34 0)
			(effects
				(font
					(size 1.27 1.27)
				)
				(justify left bottom)
				(hide yes)
			)
		)
		(property "Dielectric" "X5R"
			(at 146.05 53.34 0)
			(effects
				(font
					(size 1.27 1.27)
				)
				(justify left bottom)
				(hide yes)
			)
		)
		(pin "2"
		)
		(pin "1"
		)
		(instances
			(project "OCuLink to 10GbE adapter"
				(path ""
					(reference "C104")
					(unit 1)
				)
			)
		)
	)
	(symbol
		(lib_id "antmicropower:GND")
		(at 353.06 93.98 0)
		(unit 1)
		(exclude_from_sim no)
		(in_bom yes)
		(on_board yes)
		(dnp no)
		(property "Reference" "#PWR0169"
			(at 361.95 96.52 0)
			(effects
				(font
					(size 1.27 1.27)
					(thickness 0.15)
				)
				(justify left bottom)
				(hide yes)
			)
		)
		(property "Value" "GND"
			(at 353.06 97.79 0)
			(effects
				(font
					(size 1.27 1.27)
					(thickness 0.15)
				)
			)
		)
		(property "Footprint" ""
			(at 361.95 101.6 0)
			(effects
				(font
					(size 1.27 1.27)
					(thickness 0.15)
				)
				(justify left bottom)
				(hide yes)
			)
		)
		(property "Datasheet" ""
			(at 361.95 106.68 0)
			(effects
				(font
					(size 1.27 1.27)
					(thickness 0.15)
				)
				(justify left bottom)
				(hide yes)
			)
		)
		(property "Description" ""
			(at 353.06 93.98 0)
			(effects
				(font
					(size 1.27 1.27)
				)
				(hide yes)
			)
		)
		(property "Author" "Antmicro"
			(at 361.95 101.6 0)
			(effects
				(font
					(size 1.27 1.27)
					(thickness 0.15)
				)
				(justify left bottom)
				(hide yes)
			)
		)
		(property "License" "Apache-2.0"
			(at 361.95 104.14 0)
			(effects
				(font
					(size 1.27 1.27)
					(thickness 0.15)
				)
				(justify left bottom)
				(hide yes)
			)
		)
		(pin "1"
		)
		(instances
			(project "OCuLink to 10GbE adapter"
				(path ""
					(reference "#PWR0169")
					(unit 1)
				)
			)
		)
	)
	(symbol
		(lib_id "antmicroCapacitors0402:C_1u_25V_0402")
		(at 326.39 52.07 90)
		(unit 1)
		(exclude_from_sim no)
		(in_bom yes)
		(on_board yes)
		(dnp no)
		(property "Reference" "C90"
			(at 328.422 48.26 90)
			(effects
				(font
					(size 1.27 1.27)
					(thickness 0.15)
				)
				(justify right)
			)
		)
		(property "Value" "C_1u_25V_0402"
			(at 336.55 31.75 0)
			(effects
				(font
					(size 1.27 1.27)
					(thickness 0.15)
				)
				(justify left bottom)
				(hide yes)
			)
		)
		(property "Footprint" "antmicro-footprints:C_0402_1005Metric"
			(at 339.09 31.75 0)
			(effects
				(font
					(size 1.27 1.27)
					(thickness 0.15)
				)
				(justify left bottom)
				(hide yes)
			)
		)
		(property "Datasheet" "https://www.murata.com/products/productdetail?partno=GRM155R61E105KE11%23"
			(at 341.63 31.75 0)
			(effects
				(font
					(size 1.27 1.27)
					(thickness 0.15)
				)
				(justify left bottom)
				(hide yes)
			)
		)
		(property "Description" "SMD Multilayer Ceramic Capacitor, 1 µF, 25 V, 0402 [1005 Metric], ± 10%, X5R, GRM Series"
			(at 326.39 52.07 0)
			(effects
				(font
					(size 1.27 1.27)
				)
				(hide yes)
			)
		)
		(property "MPN" "GRM155R61E105KE11J"
			(at 344.17 31.75 0)
			(effects
				(font
					(size 1.27 1.27)
					(thickness 0.15)
				)
				(justify left bottom)
				(hide yes)
			)
		)
		(property "Manufacturer" "Murata"
			(at 346.71 31.75 0)
			(effects
				(font
					(size 1.27 1.27)
					(thickness 0.15)
				)
				(justify left bottom)
				(hide yes)
			)
		)
		(property "License" "Apache-2.0"
			(at 349.25 31.75 0)
			(effects
				(font
					(size 1.27 1.27)
					(thickness 0.15)
				)
				(justify left bottom)
				(hide yes)
			)
		)
		(property "Author" "Antmicro"
			(at 351.79 31.75 0)
			(effects
				(font
					(size 1.27 1.27)
					(thickness 0.15)
				)
				(justify left bottom)
				(hide yes)
			)
		)
		(property "Val" "1u"
			(at 328.422 50.8 90)
			(effects
				(font
					(size 1.27 1.27)
					(thickness 0.15)
				)
				(justify right)
			)
		)
		(property "Voltage" "25V"
			(at 354.33 31.75 0)
			(effects
				(font
					(size 1.27 1.27)
				)
				(justify left bottom)
				(hide yes)
			)
		)
		(property "Dielectric" "X5R"
			(at 356.87 31.75 0)
			(effects
				(font
					(size 1.27 1.27)
				)
				(justify left bottom)
				(hide yes)
			)
		)
		(pin "2"
		)
		(pin "1"
		)
		(instances
			(project "OCuLink to 10GbE adapter"
				(path ""
					(reference "C90")
					(unit 1)
				)
			)
		)
	)
	(symbol
		(lib_id "antmicropower:GND")
		(at 317.5 115.57 0)
		(unit 1)
		(exclude_from_sim no)
		(in_bom yes)
		(on_board yes)
		(dnp no)
		(property "Reference" "#PWR0179"
			(at 326.39 118.11 0)
			(effects
				(font
					(size 1.27 1.27)
					(thickness 0.15)
				)
				(justify left bottom)
				(hide yes)
			)
		)
		(property "Value" "GND"
			(at 317.5 119.38 0)
			(effects
				(font
					(size 1.27 1.27)
					(thickness 0.15)
				)
			)
		)
		(property "Footprint" ""
			(at 326.39 123.19 0)
			(effects
				(font
					(size 1.27 1.27)
					(thickness 0.15)
				)
				(justify left bottom)
				(hide yes)
			)
		)
		(property "Datasheet" ""
			(at 326.39 128.27 0)
			(effects
				(font
					(size 1.27 1.27)
					(thickness 0.15)
				)
				(justify left bottom)
				(hide yes)
			)
		)
		(property "Description" ""
			(at 317.5 115.57 0)
			(effects
				(font
					(size 1.27 1.27)
				)
				(hide yes)
			)
		)
		(property "Author" "Antmicro"
			(at 326.39 123.19 0)
			(effects
				(font
					(size 1.27 1.27)
					(thickness 0.15)
				)
				(justify left bottom)
				(hide yes)
			)
		)
		(property "License" "Apache-2.0"
			(at 326.39 125.73 0)
			(effects
				(font
					(size 1.27 1.27)
					(thickness 0.15)
				)
				(justify left bottom)
				(hide yes)
			)
		)
		(pin "1"
		)
		(instances
			(project "OCuLink to 10GbE adapter"
				(path ""
					(reference "#PWR0179")
					(unit 1)
				)
			)
		)
	)
	(symbol
		(lib_id "antmicropower:GND")
		(at 97.79 182.88 0)
		(unit 1)
		(exclude_from_sim no)
		(in_bom yes)
		(on_board yes)
		(dnp no)
		(property "Reference" "#PWR0228"
			(at 106.68 185.42 0)
			(effects
				(font
					(size 1.27 1.27)
					(thickness 0.15)
				)
				(justify left bottom)
				(hide yes)
			)
		)
		(property "Value" "GND"
			(at 97.79 186.69 0)
			(effects
				(font
					(size 1.27 1.27)
					(thickness 0.15)
				)
			)
		)
		(property "Footprint" ""
			(at 106.68 190.5 0)
			(effects
				(font
					(size 1.27 1.27)
					(thickness 0.15)
				)
				(justify left bottom)
				(hide yes)
			)
		)
		(property "Datasheet" ""
			(at 106.68 195.58 0)
			(effects
				(font
					(size 1.27 1.27)
					(thickness 0.15)
				)
				(justify left bottom)
				(hide yes)
			)
		)
		(property "Description" ""
			(at 97.79 182.88 0)
			(effects
				(font
					(size 1.27 1.27)
				)
				(hide yes)
			)
		)
		(property "Author" "Antmicro"
			(at 106.68 190.5 0)
			(effects
				(font
					(size 1.27 1.27)
					(thickness 0.15)
				)
				(justify left bottom)
				(hide yes)
			)
		)
		(property "License" "Apache-2.0"
			(at 106.68 193.04 0)
			(effects
				(font
					(size 1.27 1.27)
					(thickness 0.15)
				)
				(justify left bottom)
				(hide yes)
			)
		)
		(pin "1"
		)
		(instances
			(project "OCuLink to 10GbE adapter"
				(path ""
					(reference "#PWR0228")
					(unit 1)
				)
			)
		)
	)
	(symbol
		(lib_id "antmicroCapacitors0402:C_1u_25V_0402")
		(at 361.95 113.03 90)
		(unit 1)
		(exclude_from_sim no)
		(in_bom yes)
		(on_board yes)
		(dnp no)
		(property "Reference" "C136"
			(at 363.982 109.22 90)
			(effects
				(font
					(size 1.27 1.27)
					(thickness 0.15)
				)
				(justify right)
			)
		)
		(property "Value" "C_1u_25V_0402"
			(at 372.11 92.71 0)
			(effects
				(font
					(size 1.27 1.27)
					(thickness 0.15)
				)
				(justify left bottom)
				(hide yes)
			)
		)
		(property "Footprint" "antmicro-footprints:C_0402_1005Metric"
			(at 374.65 92.71 0)
			(effects
				(font
					(size 1.27 1.27)
					(thickness 0.15)
				)
				(justify left bottom)
				(hide yes)
			)
		)
		(property "Datasheet" "https://www.murata.com/products/productdetail?partno=GRM155R61E105KE11%23"
			(at 377.19 92.71 0)
			(effects
				(font
					(size 1.27 1.27)
					(thickness 0.15)
				)
				(justify left bottom)
				(hide yes)
			)
		)
		(property "Description" "SMD Multilayer Ceramic Capacitor, 1 µF, 25 V, 0402 [1005 Metric], ± 10%, X5R, GRM Series"
			(at 361.95 113.03 0)
			(effects
				(font
					(size 1.27 1.27)
				)
				(hide yes)
			)
		)
		(property "MPN" "GRM155R61E105KE11J"
			(at 379.73 92.71 0)
			(effects
				(font
					(size 1.27 1.27)
					(thickness 0.15)
				)
				(justify left bottom)
				(hide yes)
			)
		)
		(property "Manufacturer" "Murata"
			(at 382.27 92.71 0)
			(effects
				(font
					(size 1.27 1.27)
					(thickness 0.15)
				)
				(justify left bottom)
				(hide yes)
			)
		)
		(property "License" "Apache-2.0"
			(at 384.81 92.71 0)
			(effects
				(font
					(size 1.27 1.27)
					(thickness 0.15)
				)
				(justify left bottom)
				(hide yes)
			)
		)
		(property "Author" "Antmicro"
			(at 387.35 92.71 0)
			(effects
				(font
					(size 1.27 1.27)
					(thickness 0.15)
				)
				(justify left bottom)
				(hide yes)
			)
		)
		(property "Val" "1u"
			(at 363.982 111.76 90)
			(effects
				(font
					(size 1.27 1.27)
					(thickness 0.15)
				)
				(justify right)
			)
		)
		(property "Voltage" "25V"
			(at 389.89 92.71 0)
			(effects
				(font
					(size 1.27 1.27)
				)
				(justify left bottom)
				(hide yes)
			)
		)
		(property "Dielectric" "X5R"
			(at 392.43 92.71 0)
			(effects
				(font
					(size 1.27 1.27)
				)
				(justify left bottom)
				(hide yes)
			)
		)
		(pin "2"
		)
		(pin "1"
		)
		(instances
			(project "OCuLink to 10GbE adapter"
				(path ""
					(reference "C136")
					(unit 1)
				)
			)
		)
	)
	(symbol
		(lib_id "antmicroCapacitors0402:C_1u_25V_0402")
		(at 370.84 73.66 90)
		(unit 1)
		(exclude_from_sim no)
		(in_bom yes)
		(on_board yes)
		(dnp no)
		(property "Reference" "C113"
			(at 372.872 69.85 90)
			(effects
				(font
					(size 1.27 1.27)
					(thickness 0.15)
				)
				(justify right)
			)
		)
		(property "Value" "C_1u_25V_0402"
			(at 381 53.34 0)
			(effects
				(font
					(size 1.27 1.27)
					(thickness 0.15)
				)
				(justify left bottom)
				(hide yes)
			)
		)
		(property "Footprint" "antmicro-footprints:C_0402_1005Metric"
			(at 383.54 53.34 0)
			(effects
				(font
					(size 1.27 1.27)
					(thickness 0.15)
				)
				(justify left bottom)
				(hide yes)
			)
		)
		(property "Datasheet" "https://www.murata.com/products/productdetail?partno=GRM155R61E105KE11%23"
			(at 386.08 53.34 0)
			(effects
				(font
					(size 1.27 1.27)
					(thickness 0.15)
				)
				(justify left bottom)
				(hide yes)
			)
		)
		(property "Description" "SMD Multilayer Ceramic Capacitor, 1 µF, 25 V, 0402 [1005 Metric], ± 10%, X5R, GRM Series"
			(at 370.84 73.66 0)
			(effects
				(font
					(size 1.27 1.27)
				)
				(hide yes)
			)
		)
		(property "MPN" "GRM155R61E105KE11J"
			(at 388.62 53.34 0)
			(effects
				(font
					(size 1.27 1.27)
					(thickness 0.15)
				)
				(justify left bottom)
				(hide yes)
			)
		)
		(property "Manufacturer" "Murata"
			(at 391.16 53.34 0)
			(effects
				(font
					(size 1.27 1.27)
					(thickness 0.15)
				)
				(justify left bottom)
				(hide yes)
			)
		)
		(property "License" "Apache-2.0"
			(at 393.7 53.34 0)
			(effects
				(font
					(size 1.27 1.27)
					(thickness 0.15)
				)
				(justify left bottom)
				(hide yes)
			)
		)
		(property "Author" "Antmicro"
			(at 396.24 53.34 0)
			(effects
				(font
					(size 1.27 1.27)
					(thickness 0.15)
				)
				(justify left bottom)
				(hide yes)
			)
		)
		(property "Val" "1u"
			(at 372.872 72.39 90)
			(effects
				(font
					(size 1.27 1.27)
					(thickness 0.15)
				)
				(justify right)
			)
		)
		(property "Voltage" "25V"
			(at 398.78 53.34 0)
			(effects
				(font
					(size 1.27 1.27)
				)
				(justify left bottom)
				(hide yes)
			)
		)
		(property "Dielectric" "X5R"
			(at 401.32 53.34 0)
			(effects
				(font
					(size 1.27 1.27)
				)
				(justify left bottom)
				(hide yes)
			)
		)
		(pin "2"
		)
		(pin "1"
		)
		(instances
			(project "OCuLink to 10GbE adapter"
				(path ""
					(reference "C113")
					(unit 1)
				)
			)
		)
	)
	(symbol
		(lib_id "antmicropower:GND")
		(at 62.23 156.21 0)
		(unit 1)
		(exclude_from_sim no)
		(in_bom yes)
		(on_board yes)
		(dnp no)
		(property "Reference" "#PWR0215"
			(at 71.12 158.75 0)
			(effects
				(font
					(size 1.27 1.27)
					(thickness 0.15)
				)
				(justify left bottom)
				(hide yes)
			)
		)
		(property "Value" "GND"
			(at 62.23 160.02 0)
			(effects
				(font
					(size 1.27 1.27)
					(thickness 0.15)
				)
			)
		)
		(property "Footprint" ""
			(at 71.12 163.83 0)
			(effects
				(font
					(size 1.27 1.27)
					(thickness 0.15)
				)
				(justify left bottom)
				(hide yes)
			)
		)
		(property "Datasheet" ""
			(at 71.12 168.91 0)
			(effects
				(font
					(size 1.27 1.27)
					(thickness 0.15)
				)
				(justify left bottom)
				(hide yes)
			)
		)
		(property "Description" ""
			(at 62.23 156.21 0)
			(effects
				(font
					(size 1.27 1.27)
				)
				(hide yes)
			)
		)
		(property "Author" "Antmicro"
			(at 71.12 163.83 0)
			(effects
				(font
					(size 1.27 1.27)
					(thickness 0.15)
				)
				(justify left bottom)
				(hide yes)
			)
		)
		(property "License" "Apache-2.0"
			(at 71.12 166.37 0)
			(effects
				(font
					(size 1.27 1.27)
					(thickness 0.15)
				)
				(justify left bottom)
				(hide yes)
			)
		)
		(pin "1"
		)
		(instances
			(project "OCuLink to 10GbE adapter"
				(path ""
					(reference "#PWR0215")
					(unit 1)
				)
			)
		)
	)
	(symbol
		(lib_id "antmicropower:GND")
		(at 353.06 76.2 0)
		(unit 1)
		(exclude_from_sim no)
		(in_bom yes)
		(on_board yes)
		(dnp no)
		(property "Reference" "#PWR0145"
			(at 361.95 78.74 0)
			(effects
				(font
					(size 1.27 1.27)
					(thickness 0.15)
				)
				(justify left bottom)
				(hide yes)
			)
		)
		(property "Value" "GND"
			(at 353.06 80.01 0)
			(effects
				(font
					(size 1.27 1.27)
					(thickness 0.15)
				)
			)
		)
		(property "Footprint" ""
			(at 361.95 83.82 0)
			(effects
				(font
					(size 1.27 1.27)
					(thickness 0.15)
				)
				(justify left bottom)
				(hide yes)
			)
		)
		(property "Datasheet" ""
			(at 361.95 88.9 0)
			(effects
				(font
					(size 1.27 1.27)
					(thickness 0.15)
				)
				(justify left bottom)
				(hide yes)
			)
		)
		(property "Description" ""
			(at 353.06 76.2 0)
			(effects
				(font
					(size 1.27 1.27)
				)
				(hide yes)
			)
		)
		(property "Author" "Antmicro"
			(at 361.95 83.82 0)
			(effects
				(font
					(size 1.27 1.27)
					(thickness 0.15)
				)
				(justify left bottom)
				(hide yes)
			)
		)
		(property "License" "Apache-2.0"
			(at 361.95 86.36 0)
			(effects
				(font
					(size 1.27 1.27)
					(thickness 0.15)
				)
				(justify left bottom)
				(hide yes)
			)
		)
		(pin "1"
		)
		(instances
			(project "OCuLink to 10GbE adapter"
				(path ""
					(reference "#PWR0145")
					(unit 1)
				)
			)
		)
	)
	(symbol
		(lib_id "antmicroCapacitors0603:C_10u_10V_X7R_0603")
		(at 62.23 73.66 90)
		(unit 1)
		(exclude_from_sim no)
		(in_bom yes)
		(on_board yes)
		(dnp no)
		(property "Reference" "C100"
			(at 64.008 69.85 90)
			(effects
				(font
					(size 1.27 1.27)
					(thickness 0.15)
				)
				(justify right)
			)
		)
		(property "Value" "C_10u_10V_X7R_0603"
			(at 72.39 58.42 0)
			(effects
				(font
					(size 1.27 1.27)
					(thickness 0.15)
				)
				(justify left bottom)
				(hide yes)
			)
		)
		(property "Footprint" "antmicro-footprints:C_0603_1608Metric"
			(at 74.93 58.42 0)
			(effects
				(font
					(size 1.27 1.27)
					(thickness 0.15)
				)
				(justify left bottom)
				(hide yes)
			)
		)
		(property "Datasheet" "https://www.murata.com/products/productdetail?partno=GRM188Z71A106KA73%23"
			(at 77.47 58.42 0)
			(effects
				(font
					(size 1.27 1.27)
					(thickness 0.15)
				)
				(justify left bottom)
				(hide yes)
			)
		)
		(property "Description" "SMD Multilayer Ceramic Capacitor,  10µF, 10V, 0603, ±10%, X7R"
			(at 62.23 73.66 0)
			(effects
				(font
					(size 1.27 1.27)
				)
				(hide yes)
			)
		)
		(property "MPN" "GRM188Z71A106KA73D"
			(at 80.01 58.42 0)
			(effects
				(font
					(size 1.27 1.27)
					(thickness 0.15)
				)
				(justify left bottom)
				(hide yes)
			)
		)
		(property "Val" "10u"
			(at 64.008 72.39 90)
			(effects
				(font
					(size 1.27 1.27)
					(thickness 0.15)
				)
				(justify right)
			)
		)
		(property "Voltage" "10V"
			(at 82.55 58.42 0)
			(effects
				(font
					(size 1.27 1.27)
					(thickness 0.15)
				)
				(justify left bottom)
				(hide yes)
			)
		)
		(property "Dielectric" "X7R"
			(at 85.09 58.42 0)
			(effects
				(font
					(size 1.27 1.27)
					(thickness 0.15)
				)
				(justify left bottom)
				(hide yes)
			)
		)
		(property "Manufacturer" "Murata"
			(at 87.63 58.42 0)
			(effects
				(font
					(size 1.27 1.27)
					(thickness 0.15)
				)
				(justify left bottom)
				(hide yes)
			)
		)
		(property "License" "Apache-2.0"
			(at 90.17 58.42 0)
			(effects
				(font
					(size 1.27 1.27)
					(thickness 0.15)
				)
				(justify left bottom)
				(hide yes)
			)
		)
		(property "Author" "Antmicro"
			(at 92.71 58.42 0)
			(effects
				(font
					(size 1.27 1.27)
					(thickness 0.15)
				)
				(justify left bottom)
				(hide yes)
			)
		)
		(pin "1"
		)
		(pin "2"
		)
		(instances
			(project "OCuLink to 10GbE adapter"
				(path ""
					(reference "C100")
					(unit 1)
				)
			)
		)
	)
	(symbol
		(lib_id "antmicropower:GND")
		(at 370.84 133.35 0)
		(unit 1)
		(exclude_from_sim no)
		(in_bom yes)
		(on_board yes)
		(dnp no)
		(property "Reference" "#PWR0202"
			(at 379.73 135.89 0)
			(effects
				(font
					(size 1.27 1.27)
					(thickness 0.15)
				)
				(justify left bottom)
				(hide yes)
			)
		)
		(property "Value" "GND"
			(at 370.84 137.16 0)
			(effects
				(font
					(size 1.27 1.27)
					(thickness 0.15)
				)
			)
		)
		(property "Footprint" ""
			(at 379.73 140.97 0)
			(effects
				(font
					(size 1.27 1.27)
					(thickness 0.15)
				)
				(justify left bottom)
				(hide yes)
			)
		)
		(property "Datasheet" ""
			(at 379.73 146.05 0)
			(effects
				(font
					(size 1.27 1.27)
					(thickness 0.15)
				)
				(justify left bottom)
				(hide yes)
			)
		)
		(property "Description" ""
			(at 370.84 133.35 0)
			(effects
				(font
					(size 1.27 1.27)
				)
				(hide yes)
			)
		)
		(property "Author" "Antmicro"
			(at 379.73 140.97 0)
			(effects
				(font
					(size 1.27 1.27)
					(thickness 0.15)
				)
				(justify left bottom)
				(hide yes)
			)
		)
		(property "License" "Apache-2.0"
			(at 379.73 143.51 0)
			(effects
				(font
					(size 1.27 1.27)
					(thickness 0.15)
				)
				(justify left bottom)
				(hide yes)
			)
		)
		(pin "1"
		)
		(instances
			(project "OCuLink to 10GbE adapter"
				(path ""
					(reference "#PWR0202")
					(unit 1)
				)
			)
		)
	)
	(symbol
		(lib_id "antmicroCapacitors0402:C_1u_25V_0402")
		(at 317.5 113.03 90)
		(unit 1)
		(exclude_from_sim no)
		(in_bom yes)
		(on_board yes)
		(dnp no)
		(property "Reference" "C131"
			(at 319.532 109.22 90)
			(effects
				(font
					(size 1.27 1.27)
					(thickness 0.15)
				)
				(justify right)
			)
		)
		(property "Value" "C_1u_25V_0402"
			(at 327.66 92.71 0)
			(effects
				(font
					(size 1.27 1.27)
					(thickness 0.15)
				)
				(justify left bottom)
				(hide yes)
			)
		)
		(property "Footprint" "antmicro-footprints:C_0402_1005Metric"
			(at 330.2 92.71 0)
			(effects
				(font
					(size 1.27 1.27)
					(thickness 0.15)
				)
				(justify left bottom)
				(hide yes)
			)
		)
		(property "Datasheet" "https://www.murata.com/products/productdetail?partno=GRM155R61E105KE11%23"
			(at 332.74 92.71 0)
			(effects
				(font
					(size 1.27 1.27)
					(thickness 0.15)
				)
				(justify left bottom)
				(hide yes)
			)
		)
		(property "Description" "SMD Multilayer Ceramic Capacitor, 1 µF, 25 V, 0402 [1005 Metric], ± 10%, X5R, GRM Series"
			(at 317.5 113.03 0)
			(effects
				(font
					(size 1.27 1.27)
				)
				(hide yes)
			)
		)
		(property "MPN" "GRM155R61E105KE11J"
			(at 335.28 92.71 0)
			(effects
				(font
					(size 1.27 1.27)
					(thickness 0.15)
				)
				(justify left bottom)
				(hide yes)
			)
		)
		(property "Manufacturer" "Murata"
			(at 337.82 92.71 0)
			(effects
				(font
					(size 1.27 1.27)
					(thickness 0.15)
				)
				(justify left bottom)
				(hide yes)
			)
		)
		(property "License" "Apache-2.0"
			(at 340.36 92.71 0)
			(effects
				(font
					(size 1.27 1.27)
					(thickness 0.15)
				)
				(justify left bottom)
				(hide yes)
			)
		)
		(property "Author" "Antmicro"
			(at 342.9 92.71 0)
			(effects
				(font
					(size 1.27 1.27)
					(thickness 0.15)
				)
				(justify left bottom)
				(hide yes)
			)
		)
		(property "Val" "1u"
			(at 319.532 111.76 90)
			(effects
				(font
					(size 1.27 1.27)
					(thickness 0.15)
				)
				(justify right)
			)
		)
		(property "Voltage" "25V"
			(at 345.44 92.71 0)
			(effects
				(font
					(size 1.27 1.27)
				)
				(justify left bottom)
				(hide yes)
			)
		)
		(property "Dielectric" "X5R"
			(at 347.98 92.71 0)
			(effects
				(font
					(size 1.27 1.27)
				)
				(justify left bottom)
				(hide yes)
			)
		)
		(pin "2"
		)
		(pin "1"
		)
		(instances
			(project "OCuLink to 10GbE adapter"
				(path ""
					(reference "C131")
					(unit 1)
				)
			)
		)
	)
	(symbol
		(lib_id "antmicroCapacitors0603:C_10u_10V_X7R_0603")
		(at 309.88 149.86 270)
		(mirror x)
		(unit 1)
		(exclude_from_sim no)
		(in_bom yes)
		(on_board yes)
		(dnp no)
		(property "Reference" "C160"
			(at 307.848 146.05 90)
			(effects
				(font
					(size 1.27 1.27)
					(thickness 0.15)
				)
				(justify right)
			)
		)
		(property "Value" "C_10u_10V_X7R_0603"
			(at 299.72 134.62 0)
			(effects
				(font
					(size 1.27 1.27)
					(thickness 0.15)
				)
				(justify left bottom)
				(hide yes)
			)
		)
		(property "Footprint" "antmicro-footprints:C_0603_1608Metric"
			(at 297.18 134.62 0)
			(effects
				(font
					(size 1.27 1.27)
					(thickness 0.15)
				)
				(justify left bottom)
				(hide yes)
			)
		)
		(property "Datasheet" "https://www.murata.com/products/productdetail?partno=GRM188Z71A106KA73%23"
			(at 294.64 134.62 0)
			(effects
				(font
					(size 1.27 1.27)
					(thickness 0.15)
				)
				(justify left bottom)
				(hide yes)
			)
		)
		(property "Description" "SMD Multilayer Ceramic Capacitor,  10µF, 10V, 0603, ±10%, X7R"
			(at 309.88 149.86 0)
			(effects
				(font
					(size 1.27 1.27)
				)
				(hide yes)
			)
		)
		(property "MPN" "GRM188Z71A106KA73D"
			(at 292.1 134.62 0)
			(effects
				(font
					(size 1.27 1.27)
					(thickness 0.15)
				)
				(justify left bottom)
				(hide yes)
			)
		)
		(property "Val" "10u"
			(at 307.848 148.59 90)
			(effects
				(font
					(size 1.27 1.27)
					(thickness 0.15)
				)
				(justify right)
			)
		)
		(property "Voltage" "10V"
			(at 289.56 134.62 0)
			(effects
				(font
					(size 1.27 1.27)
					(thickness 0.15)
				)
				(justify left bottom)
				(hide yes)
			)
		)
		(property "Dielectric" "X7R"
			(at 287.02 134.62 0)
			(effects
				(font
					(size 1.27 1.27)
					(thickness 0.15)
				)
				(justify left bottom)
				(hide yes)
			)
		)
		(property "Manufacturer" "Murata"
			(at 284.48 134.62 0)
			(effects
				(font
					(size 1.27 1.27)
					(thickness 0.15)
				)
				(justify left bottom)
				(hide yes)
			)
		)
		(property "License" "Apache-2.0"
			(at 281.94 134.62 0)
			(effects
				(font
					(size 1.27 1.27)
					(thickness 0.15)
				)
				(justify left bottom)
				(hide yes)
			)
		)
		(property "Author" "Antmicro"
			(at 279.4 134.62 0)
			(effects
				(font
					(size 1.27 1.27)
					(thickness 0.15)
				)
				(justify left bottom)
				(hide yes)
			)
		)
		(pin "1"
		)
		(pin "2"
		)
		(instances
			(project "OCuLink to 10GbE adapter"
				(path ""
					(reference "C160")
					(unit 1)
				)
			)
		)
	)
	(symbol
		(lib_id "antmicropower:GND")
		(at 115.57 236.22 0)
		(unit 1)
		(exclude_from_sim no)
		(in_bom yes)
		(on_board yes)
		(dnp no)
		(property "Reference" "#PWR0241"
			(at 124.46 238.76 0)
			(effects
				(font
					(size 1.27 1.27)
					(thickness 0.15)
				)
				(justify left bottom)
				(hide yes)
			)
		)
		(property "Value" "GND"
			(at 115.57 240.03 0)
			(effects
				(font
					(size 1.27 1.27)
					(thickness 0.15)
				)
			)
		)
		(property "Footprint" ""
			(at 124.46 243.84 0)
			(effects
				(font
					(size 1.27 1.27)
					(thickness 0.15)
				)
				(justify left bottom)
				(hide yes)
			)
		)
		(property "Datasheet" ""
			(at 124.46 248.92 0)
			(effects
				(font
					(size 1.27 1.27)
					(thickness 0.15)
				)
				(justify left bottom)
				(hide yes)
			)
		)
		(property "Description" ""
			(at 115.57 236.22 0)
			(effects
				(font
					(size 1.27 1.27)
				)
				(hide yes)
			)
		)
		(property "Author" "Antmicro"
			(at 124.46 243.84 0)
			(effects
				(font
					(size 1.27 1.27)
					(thickness 0.15)
				)
				(justify left bottom)
				(hide yes)
			)
		)
		(property "License" "Apache-2.0"
			(at 124.46 246.38 0)
			(effects
				(font
					(size 1.27 1.27)
					(thickness 0.15)
				)
				(justify left bottom)
				(hide yes)
			)
		)
		(pin "1"
		)
		(instances
			(project "OCuLink to 10GbE adapter"
				(path ""
					(reference "#PWR0241")
					(unit 1)
				)
			)
		)
	)
	(symbol
		(lib_id "antmicroCapacitors0603:C_10u_10V_X7R_0603")
		(at 283.21 149.86 270)
		(mirror x)
		(unit 1)
		(exclude_from_sim no)
		(in_bom yes)
		(on_board yes)
		(dnp no)
		(property "Reference" "C157"
			(at 281.178 146.05 90)
			(effects
				(font
					(size 1.27 1.27)
					(thickness 0.15)
				)
				(justify right)
			)
		)
		(property "Value" "C_10u_10V_X7R_0603"
			(at 273.05 134.62 0)
			(effects
				(font
					(size 1.27 1.27)
					(thickness 0.15)
				)
				(justify left bottom)
				(hide yes)
			)
		)
		(property "Footprint" "antmicro-footprints:C_0603_1608Metric"
			(at 270.51 134.62 0)
			(effects
				(font
					(size 1.27 1.27)
					(thickness 0.15)
				)
				(justify left bottom)
				(hide yes)
			)
		)
		(property "Datasheet" "https://www.murata.com/products/productdetail?partno=GRM188Z71A106KA73%23"
			(at 267.97 134.62 0)
			(effects
				(font
					(size 1.27 1.27)
					(thickness 0.15)
				)
				(justify left bottom)
				(hide yes)
			)
		)
		(property "Description" "SMD Multilayer Ceramic Capacitor,  10µF, 10V, 0603, ±10%, X7R"
			(at 283.21 149.86 0)
			(effects
				(font
					(size 1.27 1.27)
				)
				(hide yes)
			)
		)
		(property "MPN" "GRM188Z71A106KA73D"
			(at 265.43 134.62 0)
			(effects
				(font
					(size 1.27 1.27)
					(thickness 0.15)
				)
				(justify left bottom)
				(hide yes)
			)
		)
		(property "Val" "10u"
			(at 281.178 148.59 90)
			(effects
				(font
					(size 1.27 1.27)
					(thickness 0.15)
				)
				(justify right)
			)
		)
		(property "Voltage" "10V"
			(at 262.89 134.62 0)
			(effects
				(font
					(size 1.27 1.27)
					(thickness 0.15)
				)
				(justify left bottom)
				(hide yes)
			)
		)
		(property "Dielectric" "X7R"
			(at 260.35 134.62 0)
			(effects
				(font
					(size 1.27 1.27)
					(thickness 0.15)
				)
				(justify left bottom)
				(hide yes)
			)
		)
		(property "Manufacturer" "Murata"
			(at 257.81 134.62 0)
			(effects
				(font
					(size 1.27 1.27)
					(thickness 0.15)
				)
				(justify left bottom)
				(hide yes)
			)
		)
		(property "License" "Apache-2.0"
			(at 255.27 134.62 0)
			(effects
				(font
					(size 1.27 1.27)
					(thickness 0.15)
				)
				(justify left bottom)
				(hide yes)
			)
		)
		(property "Author" "Antmicro"
			(at 252.73 134.62 0)
			(effects
				(font
					(size 1.27 1.27)
					(thickness 0.15)
				)
				(justify left bottom)
				(hide yes)
			)
		)
		(pin "1"
		)
		(pin "2"
		)
		(instances
			(project "OCuLink to 10GbE adapter"
				(path ""
					(reference "C157")
					(unit 1)
				)
			)
		)
	)
	(symbol
		(lib_id "antmicropower:GND")
		(at 41.91 102.87 0)
		(unit 1)
		(exclude_from_sim no)
		(in_bom yes)
		(on_board yes)
		(dnp no)
		(property "Reference" "#PWR0175"
			(at 50.8 105.41 0)
			(effects
				(font
					(size 1.27 1.27)
					(thickness 0.15)
				)
				(justify left bottom)
				(hide yes)
			)
		)
		(property "Value" "GND"
			(at 41.91 106.68 0)
			(effects
				(font
					(size 1.27 1.27)
					(thickness 0.15)
				)
			)
		)
		(property "Footprint" ""
			(at 50.8 110.49 0)
			(effects
				(font
					(size 1.27 1.27)
					(thickness 0.15)
				)
				(justify left bottom)
				(hide yes)
			)
		)
		(property "Datasheet" ""
			(at 50.8 115.57 0)
			(effects
				(font
					(size 1.27 1.27)
					(thickness 0.15)
				)
				(justify left bottom)
				(hide yes)
			)
		)
		(property "Description" ""
			(at 41.91 102.87 0)
			(effects
				(font
					(size 1.27 1.27)
				)
				(hide yes)
			)
		)
		(property "Author" "Antmicro"
			(at 50.8 110.49 0)
			(effects
				(font
					(size 1.27 1.27)
					(thickness 0.15)
				)
				(justify left bottom)
				(hide yes)
			)
		)
		(property "License" "Apache-2.0"
			(at 50.8 113.03 0)
			(effects
				(font
					(size 1.27 1.27)
					(thickness 0.15)
				)
				(justify left bottom)
				(hide yes)
			)
		)
		(pin "1"
		)
		(instances
			(project "OCuLink to 10GbE adapter"
				(path ""
					(reference "#PWR0175")
					(unit 1)
				)
			)
		)
	)
	(symbol
		(lib_id "antmicropower:GND")
		(at 62.23 54.61 0)
		(unit 1)
		(exclude_from_sim no)
		(in_bom yes)
		(on_board yes)
		(dnp no)
		(property "Reference" "#PWR0115"
			(at 71.12 57.15 0)
			(effects
				(font
					(size 1.27 1.27)
					(thickness 0.15)
				)
				(justify left bottom)
				(hide yes)
			)
		)
		(property "Value" "GND"
			(at 62.23 58.42 0)
			(effects
				(font
					(size 1.27 1.27)
					(thickness 0.15)
				)
			)
		)
		(property "Footprint" ""
			(at 71.12 62.23 0)
			(effects
				(font
					(size 1.27 1.27)
					(thickness 0.15)
				)
				(justify left bottom)
				(hide yes)
			)
		)
		(property "Datasheet" ""
			(at 71.12 67.31 0)
			(effects
				(font
					(size 1.27 1.27)
					(thickness 0.15)
				)
				(justify left bottom)
				(hide yes)
			)
		)
		(property "Description" ""
			(at 62.23 54.61 0)
			(effects
				(font
					(size 1.27 1.27)
				)
				(hide yes)
			)
		)
		(property "Author" "Antmicro"
			(at 71.12 62.23 0)
			(effects
				(font
					(size 1.27 1.27)
					(thickness 0.15)
				)
				(justify left bottom)
				(hide yes)
			)
		)
		(property "License" "Apache-2.0"
			(at 71.12 64.77 0)
			(effects
				(font
					(size 1.27 1.27)
					(thickness 0.15)
				)
				(justify left bottom)
				(hide yes)
			)
		)
		(pin "1"
		)
		(instances
			(project "OCuLink to 10GbE adapter"
				(path ""
					(reference "#PWR0115")
					(unit 1)
				)
			)
		)
	)
	(symbol
		(lib_id "antmicroFerriteBeadsandChips:FB_470Z_1A_Murata-BLM18PG_0603")
		(at 44.45 252.73 0)
		(unit 1)
		(exclude_from_sim no)
		(in_bom yes)
		(on_board yes)
		(dnp no)
		(fields_autoplaced yes)
		(property "Reference" "FB7"
			(at 46.9519 246.38 0)
			(effects
				(font
					(size 1.27 1.27)
					(thickness 0.15)
				)
			)
		)
		(property "Value" "FB_470Z_1A_Murata-BLM18PG_0603"
			(at 58.42 255.27 0)
			(effects
				(font
					(size 1.27 1.27)
					(thickness 0.15)
				)
				(justify left bottom)
				(hide yes)
			)
		)
		(property "Footprint" "antmicro-footprints:FB_0603_1608Metric"
			(at 58.42 260.35 0)
			(effects
				(font
					(size 1.27 1.27)
					(thickness 0.15)
				)
				(justify left bottom)
				(hide yes)
			)
		)
		(property "Datasheet" "https://www.murata.com/en-us/products/productdata/8796738650142/ENFA0003.pdf"
			(at 58.42 262.89 0)
			(effects
				(font
					(size 1.27 1.27)
					(thickness 0.15)
				)
				(justify left bottom)
				(hide yes)
			)
		)
		(property "Description" "Ferrite Bead, 0603 [1608 Metric], 470 ohm, 1 A, BLM18P, 0.2 ohm, ± 25%, DC power line"
			(at 44.45 252.73 0)
			(effects
				(font
					(size 1.27 1.27)
				)
				(hide yes)
			)
		)
		(property "Val" "470Z/1A"
			(at 46.9519 248.92 0)
			(effects
				(font
					(size 1.27 1.27)
				)
			)
		)
		(property "MPN" "BLM18PG471SN1D"
			(at 58.42 265.43 0)
			(effects
				(font
					(size 1.27 1.27)
					(thickness 0.15)
				)
				(justify left bottom)
				(hide yes)
			)
		)
		(property "Manufacturer" "Murata"
			(at 58.42 267.97 0)
			(effects
				(font
					(size 1.27 1.27)
					(thickness 0.15)
				)
				(justify left bottom)
				(hide yes)
			)
		)
		(property "Current" ""
			(at 64.77 275.59 0)
			(effects
				(font
					(size 1.27 1.27)
					(thickness 0.15)
				)
				(justify left bottom)
				(hide yes)
			)
		)
		(property "Author" "Antmicro"
			(at 58.42 270.51 0)
			(effects
				(font
					(size 1.27 1.27)
					(thickness 0.15)
				)
				(justify left bottom)
				(hide yes)
			)
		)
		(property "License" "Apache-2.0"
			(at 58.42 273.05 0)
			(effects
				(font
					(size 1.27 1.27)
					(thickness 0.15)
				)
				(justify left bottom)
				(hide yes)
			)
		)
		(pin "2"
		)
		(pin "1"
		)
		(instances
			(project ""
				(path ""
					(reference "FB7")
					(unit 1)
				)
			)
		)
	)
	(symbol
		(lib_id "antmicropower:GND")
		(at 397.51 93.98 0)
		(unit 1)
		(exclude_from_sim no)
		(in_bom yes)
		(on_board yes)
		(dnp no)
		(property "Reference" "#PWR0174"
			(at 406.4 96.52 0)
			(effects
				(font
					(size 1.27 1.27)
					(thickness 0.15)
				)
				(justify left bottom)
				(hide yes)
			)
		)
		(property "Value" "GND"
			(at 397.51 97.79 0)
			(effects
				(font
					(size 1.27 1.27)
					(thickness 0.15)
				)
			)
		)
		(property "Footprint" ""
			(at 406.4 101.6 0)
			(effects
				(font
					(size 1.27 1.27)
					(thickness 0.15)
				)
				(justify left bottom)
				(hide yes)
			)
		)
		(property "Datasheet" ""
			(at 406.4 106.68 0)
			(effects
				(font
					(size 1.27 1.27)
					(thickness 0.15)
				)
				(justify left bottom)
				(hide yes)
			)
		)
		(property "Description" ""
			(at 397.51 93.98 0)
			(effects
				(font
					(size 1.27 1.27)
				)
				(hide yes)
			)
		)
		(property "Author" "Antmicro"
			(at 406.4 101.6 0)
			(effects
				(font
					(size 1.27 1.27)
					(thickness 0.15)
				)
				(justify left bottom)
				(hide yes)
			)
		)
		(property "License" "Apache-2.0"
			(at 406.4 104.14 0)
			(effects
				(font
					(size 1.27 1.27)
					(thickness 0.15)
				)
				(justify left bottom)
				(hide yes)
			)
		)
		(pin "1"
		)
		(instances
			(project "OCuLink to 10GbE adapter"
				(path ""
					(reference "#PWR0174")
					(unit 1)
				)
			)
		)
	)
	(symbol
		(lib_id "antmicroCapacitors0603:C_10u_10V_X7R_0603")
		(at 62.23 127 90)
		(unit 1)
		(exclude_from_sim no)
		(in_bom yes)
		(on_board yes)
		(dnp no)
		(property "Reference" "C140"
			(at 64.008 123.19 90)
			(effects
				(font
					(size 1.27 1.27)
					(thickness 0.15)
				)
				(justify right)
			)
		)
		(property "Value" "C_10u_10V_X7R_0603"
			(at 72.39 111.76 0)
			(effects
				(font
					(size 1.27 1.27)
					(thickness 0.15)
				)
				(justify left bottom)
				(hide yes)
			)
		)
		(property "Footprint" "antmicro-footprints:C_0603_1608Metric"
			(at 74.93 111.76 0)
			(effects
				(font
					(size 1.27 1.27)
					(thickness 0.15)
				)
				(justify left bottom)
				(hide yes)
			)
		)
		(property "Datasheet" "https://www.murata.com/products/productdetail?partno=GRM188Z71A106KA73%23"
			(at 77.47 111.76 0)
			(effects
				(font
					(size 1.27 1.27)
					(thickness 0.15)
				)
				(justify left bottom)
				(hide yes)
			)
		)
		(property "Description" "SMD Multilayer Ceramic Capacitor,  10µF, 10V, 0603, ±10%, X7R"
			(at 62.23 127 0)
			(effects
				(font
					(size 1.27 1.27)
				)
				(hide yes)
			)
		)
		(property "MPN" "GRM188Z71A106KA73D"
			(at 80.01 111.76 0)
			(effects
				(font
					(size 1.27 1.27)
					(thickness 0.15)
				)
				(justify left bottom)
				(hide yes)
			)
		)
		(property "Val" "10u"
			(at 64.008 125.73 90)
			(effects
				(font
					(size 1.27 1.27)
					(thickness 0.15)
				)
				(justify right)
			)
		)
		(property "Voltage" "10V"
			(at 82.55 111.76 0)
			(effects
				(font
					(size 1.27 1.27)
					(thickness 0.15)
				)
				(justify left bottom)
				(hide yes)
			)
		)
		(property "Dielectric" "X7R"
			(at 85.09 111.76 0)
			(effects
				(font
					(size 1.27 1.27)
					(thickness 0.15)
				)
				(justify left bottom)
				(hide yes)
			)
		)
		(property "Manufacturer" "Murata"
			(at 87.63 111.76 0)
			(effects
				(font
					(size 1.27 1.27)
					(thickness 0.15)
				)
				(justify left bottom)
				(hide yes)
			)
		)
		(property "License" "Apache-2.0"
			(at 90.17 111.76 0)
			(effects
				(font
					(size 1.27 1.27)
					(thickness 0.15)
				)
				(justify left bottom)
				(hide yes)
			)
		)
		(property "Author" "Antmicro"
			(at 92.71 111.76 0)
			(effects
				(font
					(size 1.27 1.27)
					(thickness 0.15)
				)
				(justify left bottom)
				(hide yes)
			)
		)
		(pin "1"
		)
		(pin "2"
		)
		(instances
			(project "OCuLink to 10GbE adapter"
				(path ""
					(reference "C140")
					(unit 1)
				)
			)
		)
	)
	(symbol
		(lib_id "antmicroCapacitors0603:C_22u_16V_0603")
		(at 344.17 130.81 90)
		(unit 1)
		(exclude_from_sim no)
		(in_bom yes)
		(on_board yes)
		(dnp no)
		(fields_autoplaced yes)
		(property "Reference" "C150"
			(at 346.71 126.9936 90)
			(effects
				(font
					(size 1.27 1.27)
					(thickness 0.15)
				)
				(justify right)
			)
		)
		(property "Value" "C_22u_16V_0603"
			(at 354.33 110.49 0)
			(effects
				(font
					(size 1.27 1.27)
					(thickness 0.15)
				)
				(justify left bottom)
				(hide yes)
			)
		)
		(property "Footprint" "antmicro-footprints:C_0603_1608Metric_EIA"
			(at 356.87 110.49 0)
			(effects
				(font
					(size 1.27 1.27)
					(thickness 0.15)
				)
				(justify left bottom)
				(hide yes)
			)
		)
		(property "Datasheet" "https://product.samsungsem.com/mlcc/CL10A226MO7JZN.do"
			(at 359.41 110.49 0)
			(effects
				(font
					(size 1.27 1.27)
					(thickness 0.15)
				)
				(justify left bottom)
				(hide yes)
			)
		)
		(property "Description" "SMD Multilayer Ceramic Capacitor"
			(at 344.17 130.81 0)
			(effects
				(font
					(size 1.27 1.27)
				)
				(hide yes)
			)
		)
		(property "MPN" "CL10A226MO7JZNC"
			(at 361.95 110.49 0)
			(effects
				(font
					(size 1.27 1.27)
					(thickness 0.15)
				)
				(justify left bottom)
				(hide yes)
			)
		)
		(property "Manufacturer" "Samsung Electro-Mechanics"
			(at 364.49 110.49 0)
			(effects
				(font
					(size 1.27 1.27)
					(thickness 0.15)
				)
				(justify left bottom)
				(hide yes)
			)
		)
		(property "License" "Apache-2.0"
			(at 367.03 110.49 0)
			(effects
				(font
					(size 1.27 1.27)
					(thickness 0.15)
				)
				(justify left bottom)
				(hide yes)
			)
		)
		(property "Author" "Antmicro"
			(at 369.57 110.49 0)
			(effects
				(font
					(size 1.27 1.27)
					(thickness 0.15)
				)
				(justify left bottom)
				(hide yes)
			)
		)
		(property "Val" "22u"
			(at 346.71 129.5336 90)
			(effects
				(font
					(size 1.27 1.27)
					(thickness 0.15)
				)
				(justify right)
			)
		)
		(property "Voltage" "16V"
			(at 372.11 110.49 0)
			(effects
				(font
					(size 1.27 1.27)
				)
				(justify left bottom)
				(hide yes)
			)
		)
		(property "Dielectric" ""
			(at 374.65 110.49 0)
			(effects
				(font
					(size 1.27 1.27)
				)
				(justify left bottom)
				(hide yes)
			)
		)
		(pin "1"
		)
		(pin "2"
		)
		(instances
			(project "OCuLink to 10GbE adapter"
				(path ""
					(reference "C150")
					(unit 1)
				)
			)
		)
	)
	(symbol
		(lib_id "antmicropower:GND")
		(at 308.61 93.98 0)
		(unit 1)
		(exclude_from_sim no)
		(in_bom yes)
		(on_board yes)
		(dnp no)
		(property "Reference" "#PWR0165"
			(at 317.5 96.52 0)
			(effects
				(font
					(size 1.27 1.27)
					(thickness 0.15)
				)
				(justify left bottom)
				(hide yes)
			)
		)
		(property "Value" "GND"
			(at 308.61 97.79 0)
			(effects
				(font
					(size 1.27 1.27)
					(thickness 0.15)
				)
			)
		)
		(property "Footprint" ""
			(at 317.5 101.6 0)
			(effects
				(font
					(size 1.27 1.27)
					(thickness 0.15)
				)
				(justify left bottom)
				(hide yes)
			)
		)
		(property "Datasheet" ""
			(at 317.5 106.68 0)
			(effects
				(font
					(size 1.27 1.27)
					(thickness 0.15)
				)
				(justify left bottom)
				(hide yes)
			)
		)
		(property "Description" ""
			(at 308.61 93.98 0)
			(effects
				(font
					(size 1.27 1.27)
				)
				(hide yes)
			)
		)
		(property "Author" "Antmicro"
			(at 317.5 101.6 0)
			(effects
				(font
					(size 1.27 1.27)
					(thickness 0.15)
				)
				(justify left bottom)
				(hide yes)
			)
		)
		(property "License" "Apache-2.0"
			(at 317.5 104.14 0)
			(effects
				(font
					(size 1.27 1.27)
					(thickness 0.15)
				)
				(justify left bottom)
				(hide yes)
			)
		)
		(pin "1"
		)
		(instances
			(project "OCuLink to 10GbE adapter"
				(path ""
					(reference "#PWR0165")
					(unit 1)
				)
			)
		)
	)
	(symbol
		(lib_id "antmicropower:GND")
		(at 370.84 115.57 0)
		(unit 1)
		(exclude_from_sim no)
		(in_bom yes)
		(on_board yes)
		(dnp no)
		(property "Reference" "#PWR0185"
			(at 379.73 118.11 0)
			(effects
				(font
					(size 1.27 1.27)
					(thickness 0.15)
				)
				(justify left bottom)
				(hide yes)
			)
		)
		(property "Value" "GND"
			(at 370.84 119.38 0)
			(effects
				(font
					(size 1.27 1.27)
					(thickness 0.15)
				)
			)
		)
		(property "Footprint" ""
			(at 379.73 123.19 0)
			(effects
				(font
					(size 1.27 1.27)
					(thickness 0.15)
				)
				(justify left bottom)
				(hide yes)
			)
		)
		(property "Datasheet" ""
			(at 379.73 128.27 0)
			(effects
				(font
					(size 1.27 1.27)
					(thickness 0.15)
				)
				(justify left bottom)
				(hide yes)
			)
		)
		(property "Description" ""
			(at 370.84 115.57 0)
			(effects
				(font
					(size 1.27 1.27)
				)
				(hide yes)
			)
		)
		(property "Author" "Antmicro"
			(at 379.73 123.19 0)
			(effects
				(font
					(size 1.27 1.27)
					(thickness 0.15)
				)
				(justify left bottom)
				(hide yes)
			)
		)
		(property "License" "Apache-2.0"
			(at 379.73 125.73 0)
			(effects
				(font
					(size 1.27 1.27)
					(thickness 0.15)
				)
				(justify left bottom)
				(hide yes)
			)
		)
		(pin "1"
		)
		(instances
			(project "OCuLink to 10GbE adapter"
				(path ""
					(reference "#PWR0185")
					(unit 1)
				)
			)
		)
	)
	(symbol
		(lib_id "antmicropower:+1V8")
		(at 21.59 116.84 0)
		(unit 1)
		(exclude_from_sim no)
		(in_bom yes)
		(on_board yes)
		(dnp no)
		(property "Reference" "#PWR0186"
			(at 36.83 119.38 0)
			(effects
				(font
					(size 1.27 1.27)
					(thickness 0.15)
				)
				(justify left bottom)
				(hide yes)
			)
		)
		(property "Value" "+1V88"
			(at 21.59 113.03 0)
			(effects
				(font
					(size 1.27 1.27)
					(thickness 0.15)
				)
			)
		)
		(property "Footprint" ""
			(at 36.83 124.46 0)
			(effects
				(font
					(size 1.27 1.27)
					(thickness 0.15)
				)
				(justify left bottom)
				(hide yes)
			)
		)
		(property "Datasheet" ""
			(at 36.83 127 0)
			(effects
				(font
					(size 1.27 1.27)
					(thickness 0.15)
				)
				(justify left bottom)
				(hide yes)
			)
		)
		(property "Description" ""
			(at 21.59 116.84 0)
			(effects
				(font
					(size 1.27 1.27)
				)
				(hide yes)
			)
		)
		(property "Author" "Antmicro"
			(at 36.83 121.92 0)
			(effects
				(font
					(size 1.27 1.27)
					(thickness 0.15)
				)
				(justify left bottom)
				(hide yes)
			)
		)
		(property "License" "Apache-2.0"
			(at 36.83 124.46 0)
			(effects
				(font
					(size 1.27 1.27)
					(thickness 0.15)
				)
				(justify left bottom)
				(hide yes)
			)
		)
		(pin "1"
		)
		(instances
			(project "OCuLink to 10GbE adapter"
				(path ""
					(reference "#PWR0186")
					(unit 1)
				)
			)
		)
	)
	(symbol
		(lib_id "antmicropower:GND")
		(at 308.61 54.61 0)
		(unit 1)
		(exclude_from_sim no)
		(in_bom yes)
		(on_board yes)
		(dnp no)
		(property "Reference" "#PWR0122"
			(at 317.5 57.15 0)
			(effects
				(font
					(size 1.27 1.27)
					(thickness 0.15)
				)
				(justify left bottom)
				(hide yes)
			)
		)
		(property "Value" "GND"
			(at 308.61 58.42 0)
			(effects
				(font
					(size 1.27 1.27)
					(thickness 0.15)
				)
			)
		)
		(property "Footprint" ""
			(at 317.5 62.23 0)
			(effects
				(font
					(size 1.27 1.27)
					(thickness 0.15)
				)
				(justify left bottom)
				(hide yes)
			)
		)
		(property "Datasheet" ""
			(at 317.5 67.31 0)
			(effects
				(font
					(size 1.27 1.27)
					(thickness 0.15)
				)
				(justify left bottom)
				(hide yes)
			)
		)
		(property "Description" ""
			(at 308.61 54.61 0)
			(effects
				(font
					(size 1.27 1.27)
				)
				(hide yes)
			)
		)
		(property "Author" "Antmicro"
			(at 317.5 62.23 0)
			(effects
				(font
					(size 1.27 1.27)
					(thickness 0.15)
				)
				(justify left bottom)
				(hide yes)
			)
		)
		(property "License" "Apache-2.0"
			(at 317.5 64.77 0)
			(effects
				(font
					(size 1.27 1.27)
					(thickness 0.15)
				)
				(justify left bottom)
				(hide yes)
			)
		)
		(pin "1"
		)
		(instances
			(project "OCuLink to 10GbE adapter"
				(path ""
					(reference "#PWR0122")
					(unit 1)
				)
			)
		)
	)
	(symbol
		(lib_id "antmicropower:GND")
		(at 283.21 152.4 0)
		(unit 1)
		(exclude_from_sim no)
		(in_bom yes)
		(on_board yes)
		(dnp no)
		(property "Reference" "#PWR0207"
			(at 292.1 154.94 0)
			(effects
				(font
					(size 1.27 1.27)
					(thickness 0.15)
				)
				(justify left bottom)
				(hide yes)
			)
		)
		(property "Value" "GND"
			(at 283.21 156.21 0)
			(effects
				(font
					(size 1.27 1.27)
					(thickness 0.15)
				)
			)
		)
		(property "Footprint" ""
			(at 292.1 160.02 0)
			(effects
				(font
					(size 1.27 1.27)
					(thickness 0.15)
				)
				(justify left bottom)
				(hide yes)
			)
		)
		(property "Datasheet" ""
			(at 292.1 165.1 0)
			(effects
				(font
					(size 1.27 1.27)
					(thickness 0.15)
				)
				(justify left bottom)
				(hide yes)
			)
		)
		(property "Description" ""
			(at 283.21 152.4 0)
			(effects
				(font
					(size 1.27 1.27)
				)
				(hide yes)
			)
		)
		(property "Author" "Antmicro"
			(at 292.1 160.02 0)
			(effects
				(font
					(size 1.27 1.27)
					(thickness 0.15)
				)
				(justify left bottom)
				(hide yes)
			)
		)
		(property "License" "Apache-2.0"
			(at 292.1 162.56 0)
			(effects
				(font
					(size 1.27 1.27)
					(thickness 0.15)
				)
				(justify left bottom)
				(hide yes)
			)
		)
		(pin "1"
		)
		(instances
			(project "OCuLink to 10GbE adapter"
				(path ""
					(reference "#PWR0207")
					(unit 1)
				)
			)
		)
	)
	(symbol
		(lib_id "antmicropower:GND")
		(at 292.1 152.4 0)
		(unit 1)
		(exclude_from_sim no)
		(in_bom yes)
		(on_board yes)
		(dnp no)
		(property "Reference" "#PWR0208"
			(at 300.99 154.94 0)
			(effects
				(font
					(size 1.27 1.27)
					(thickness 0.15)
				)
				(justify left bottom)
				(hide yes)
			)
		)
		(property "Value" "GND"
			(at 292.1 156.21 0)
			(effects
				(font
					(size 1.27 1.27)
					(thickness 0.15)
				)
			)
		)
		(property "Footprint" ""
			(at 300.99 160.02 0)
			(effects
				(font
					(size 1.27 1.27)
					(thickness 0.15)
				)
				(justify left bottom)
				(hide yes)
			)
		)
		(property "Datasheet" ""
			(at 300.99 165.1 0)
			(effects
				(font
					(size 1.27 1.27)
					(thickness 0.15)
				)
				(justify left bottom)
				(hide yes)
			)
		)
		(property "Description" ""
			(at 292.1 152.4 0)
			(effects
				(font
					(size 1.27 1.27)
				)
				(hide yes)
			)
		)
		(property "Author" "Antmicro"
			(at 300.99 160.02 0)
			(effects
				(font
					(size 1.27 1.27)
					(thickness 0.15)
				)
				(justify left bottom)
				(hide yes)
			)
		)
		(property "License" "Apache-2.0"
			(at 300.99 162.56 0)
			(effects
				(font
					(size 1.27 1.27)
					(thickness 0.15)
				)
				(justify left bottom)
				(hide yes)
			)
		)
		(pin "1"
		)
		(instances
			(project "OCuLink to 10GbE adapter"
				(path ""
					(reference "#PWR0208")
					(unit 1)
				)
			)
		)
	)
	(symbol
		(lib_id "antmicropower:+1V0")
		(at 21.59 196.85 0)
		(unit 1)
		(exclude_from_sim no)
		(in_bom yes)
		(on_board yes)
		(dnp no)
		(property "Reference" "#PWR0231"
			(at 21.59 200.66 0)
			(effects
				(font
					(size 1.27 1.27)
				)
				(hide yes)
			)
		)
		(property "Value" "+1V0"
			(at 21.59 192.786 0)
			(effects
				(font
					(size 1.27 1.27)
				)
			)
		)
		(property "Footprint" ""
			(at 21.59 196.85 0)
			(effects
				(font
					(size 1.27 1.27)
				)
				(hide yes)
			)
		)
		(property "Datasheet" ""
			(at 21.59 196.85 0)
			(effects
				(font
					(size 1.27 1.27)
				)
				(hide yes)
			)
		)
		(property "Description" ""
			(at 21.59 196.85 0)
			(effects
				(font
					(size 1.27 1.27)
				)
				(hide yes)
			)
		)
		(pin "1"
		)
		(instances
			(project "OCuLink to 10GbE adapter"
				(path ""
					(reference "#PWR0231")
					(unit 1)
				)
			)
		)
	)
	(symbol
		(lib_id "antmicroCapacitors0402:C_1u_25V_0402")
		(at 326.39 91.44 90)
		(unit 1)
		(exclude_from_sim no)
		(in_bom yes)
		(on_board yes)
		(dnp no)
		(property "Reference" "C120"
			(at 328.422 87.63 90)
			(effects
				(font
					(size 1.27 1.27)
					(thickness 0.15)
				)
				(justify right)
			)
		)
		(property "Value" "C_1u_25V_0402"
			(at 336.55 71.12 0)
			(effects
				(font
					(size 1.27 1.27)
					(thickness 0.15)
				)
				(justify left bottom)
				(hide yes)
			)
		)
		(property "Footprint" "antmicro-footprints:C_0402_1005Metric"
			(at 339.09 71.12 0)
			(effects
				(font
					(size 1.27 1.27)
					(thickness 0.15)
				)
				(justify left bottom)
				(hide yes)
			)
		)
		(property "Datasheet" "https://www.murata.com/products/productdetail?partno=GRM155R61E105KE11%23"
			(at 341.63 71.12 0)
			(effects
				(font
					(size 1.27 1.27)
					(thickness 0.15)
				)
				(justify left bottom)
				(hide yes)
			)
		)
		(property "Description" "SMD Multilayer Ceramic Capacitor, 1 µF, 25 V, 0402 [1005 Metric], ± 10%, X5R, GRM Series"
			(at 326.39 91.44 0)
			(effects
				(font
					(size 1.27 1.27)
				)
				(hide yes)
			)
		)
		(property "MPN" "GRM155R61E105KE11J"
			(at 344.17 71.12 0)
			(effects
				(font
					(size 1.27 1.27)
					(thickness 0.15)
				)
				(justify left bottom)
				(hide yes)
			)
		)
		(property "Manufacturer" "Murata"
			(at 346.71 71.12 0)
			(effects
				(font
					(size 1.27 1.27)
					(thickness 0.15)
				)
				(justify left bottom)
				(hide yes)
			)
		)
		(property "License" "Apache-2.0"
			(at 349.25 71.12 0)
			(effects
				(font
					(size 1.27 1.27)
					(thickness 0.15)
				)
				(justify left bottom)
				(hide yes)
			)
		)
		(property "Author" "Antmicro"
			(at 351.79 71.12 0)
			(effects
				(font
					(size 1.27 1.27)
					(thickness 0.15)
				)
				(justify left bottom)
				(hide yes)
			)
		)
		(property "Val" "1u"
			(at 328.422 90.17 90)
			(effects
				(font
					(size 1.27 1.27)
					(thickness 0.15)
				)
				(justify right)
			)
		)
		(property "Voltage" "25V"
			(at 354.33 71.12 0)
			(effects
				(font
					(size 1.27 1.27)
				)
				(justify left bottom)
				(hide yes)
			)
		)
		(property "Dielectric" "X5R"
			(at 356.87 71.12 0)
			(effects
				(font
					(size 1.27 1.27)
				)
				(justify left bottom)
				(hide yes)
			)
		)
		(pin "2"
		)
		(pin "1"
		)
		(instances
			(project "OCuLink to 10GbE adapter"
				(path ""
					(reference "C120")
					(unit 1)
				)
			)
		)
	)
	(symbol
		(lib_id "antmicroCapacitors0402:C_100n_0402")
		(at 39.37 260.35 90)
		(unit 1)
		(exclude_from_sim no)
		(in_bom yes)
		(on_board yes)
		(dnp no)
		(property "Reference" "C188"
			(at 41.402 256.54 90)
			(effects
				(font
					(size 1.27 1.27)
					(thickness 0.15)
				)
				(justify right)
			)
		)
		(property "Value" "C_100n_0402"
			(at 62.23 245.11 0)
			(effects
				(font
					(size 1.27 1.27)
					(thickness 0.15)
				)
				(justify left bottom)
				(hide yes)
			)
		)
		(property "Footprint" "antmicro-footprints:C_0402_1005Metric"
			(at 64.77 245.11 0)
			(effects
				(font
					(size 1.27 1.27)
					(thickness 0.15)
				)
				(justify left bottom)
				(hide yes)
			)
		)
		(property "Datasheet" "https://www.murata.com/products/productdetail?partno=GRM155R61H104KE14%23"
			(at 67.31 245.11 0)
			(effects
				(font
					(size 1.27 1.27)
					(thickness 0.15)
				)
				(justify left bottom)
				(hide yes)
			)
		)
		(property "Description" "SMD Multilayer Ceramic Capacitor, 0.1 µF, 50 V, 0402 [1005 Metric], ± 10%, X5R, GRM Series"
			(at 39.37 260.35 0)
			(effects
				(font
					(size 1.27 1.27)
				)
				(hide yes)
			)
		)
		(property "MPN" "GRM155R61H104KE14D"
			(at 69.85 245.11 0)
			(effects
				(font
					(size 1.27 1.27)
					(thickness 0.15)
				)
				(justify left bottom)
				(hide yes)
			)
		)
		(property "Val" "100n"
			(at 41.402 259.08 90)
			(effects
				(font
					(size 1.27 1.27)
					(thickness 0.15)
				)
				(justify right)
			)
		)
		(property "Voltage" "50V"
			(at 49.53 245.11 0)
			(effects
				(font
					(size 1.27 1.27)
					(thickness 0.15)
				)
				(justify left bottom)
				(hide yes)
			)
		)
		(property "Dielectric" "X5R"
			(at 52.07 245.11 0)
			(effects
				(font
					(size 1.27 1.27)
					(thickness 0.15)
				)
				(justify left bottom)
				(hide yes)
			)
		)
		(property "Manufacturer" "Murata"
			(at 54.61 245.11 0)
			(effects
				(font
					(size 1.27 1.27)
					(thickness 0.15)
				)
				(justify left bottom)
				(hide yes)
			)
		)
		(property "License" "Apache-2.0"
			(at 57.15 245.11 0)
			(effects
				(font
					(size 1.27 1.27)
					(thickness 0.15)
				)
				(justify left bottom)
				(hide yes)
			)
		)
		(property "Author" "Antmicro"
			(at 59.69 245.11 0)
			(effects
				(font
					(size 1.27 1.27)
					(thickness 0.15)
				)
				(justify left bottom)
				(hide yes)
			)
		)
		(pin "2"
		)
		(pin "1"
		)
		(instances
			(project "OCuLink to 10GbE adapter"
				(path ""
					(reference "C188")
					(unit 1)
				)
			)
		)
	)
	(symbol
		(lib_id "antmicroCapacitors0402:C_1u_25V_0402")
		(at 317.5 91.44 90)
		(unit 1)
		(exclude_from_sim no)
		(in_bom yes)
		(on_board yes)
		(dnp no)
		(property "Reference" "C119"
			(at 319.532 87.63 90)
			(effects
				(font
					(size 1.27 1.27)
					(thickness 0.15)
				)
				(justify right)
			)
		)
		(property "Value" "C_1u_25V_0402"
			(at 327.66 71.12 0)
			(effects
				(font
					(size 1.27 1.27)
					(thickness 0.15)
				)
				(justify left bottom)
				(hide yes)
			)
		)
		(property "Footprint" "antmicro-footprints:C_0402_1005Metric"
			(at 330.2 71.12 0)
			(effects
				(font
					(size 1.27 1.27)
					(thickness 0.15)
				)
				(justify left bottom)
				(hide yes)
			)
		)
		(property "Datasheet" "https://www.murata.com/products/productdetail?partno=GRM155R61E105KE11%23"
			(at 332.74 71.12 0)
			(effects
				(font
					(size 1.27 1.27)
					(thickness 0.15)
				)
				(justify left bottom)
				(hide yes)
			)
		)
		(property "Description" "SMD Multilayer Ceramic Capacitor, 1 µF, 25 V, 0402 [1005 Metric], ± 10%, X5R, GRM Series"
			(at 317.5 91.44 0)
			(effects
				(font
					(size 1.27 1.27)
				)
				(hide yes)
			)
		)
		(property "MPN" "GRM155R61E105KE11J"
			(at 335.28 71.12 0)
			(effects
				(font
					(size 1.27 1.27)
					(thickness 0.15)
				)
				(justify left bottom)
				(hide yes)
			)
		)
		(property "Manufacturer" "Murata"
			(at 337.82 71.12 0)
			(effects
				(font
					(size 1.27 1.27)
					(thickness 0.15)
				)
				(justify left bottom)
				(hide yes)
			)
		)
		(property "License" "Apache-2.0"
			(at 340.36 71.12 0)
			(effects
				(font
					(size 1.27 1.27)
					(thickness 0.15)
				)
				(justify left bottom)
				(hide yes)
			)
		)
		(property "Author" "Antmicro"
			(at 342.9 71.12 0)
			(effects
				(font
					(size 1.27 1.27)
					(thickness 0.15)
				)
				(justify left bottom)
				(hide yes)
			)
		)
		(property "Val" "1u"
			(at 319.532 90.17 90)
			(effects
				(font
					(size 1.27 1.27)
					(thickness 0.15)
				)
				(justify right)
			)
		)
		(property "Voltage" "25V"
			(at 345.44 71.12 0)
			(effects
				(font
					(size 1.27 1.27)
				)
				(justify left bottom)
				(hide yes)
			)
		)
		(property "Dielectric" "X5R"
			(at 347.98 71.12 0)
			(effects
				(font
					(size 1.27 1.27)
				)
				(justify left bottom)
				(hide yes)
			)
		)
		(pin "2"
		)
		(pin "1"
		)
		(instances
			(project "OCuLink to 10GbE adapter"
				(path ""
					(reference "C119")
					(unit 1)
				)
			)
		)
	)
	(symbol
		(lib_id "antmicropower:GND")
		(at 308.61 76.2 0)
		(unit 1)
		(exclude_from_sim no)
		(in_bom yes)
		(on_board yes)
		(dnp no)
		(property "Reference" "#PWR0140"
			(at 317.5 78.74 0)
			(effects
				(font
					(size 1.27 1.27)
					(thickness 0.15)
				)
				(justify left bottom)
				(hide yes)
			)
		)
		(property "Value" "GND"
			(at 308.61 80.01 0)
			(effects
				(font
					(size 1.27 1.27)
					(thickness 0.15)
				)
			)
		)
		(property "Footprint" ""
			(at 317.5 83.82 0)
			(effects
				(font
					(size 1.27 1.27)
					(thickness 0.15)
				)
				(justify left bottom)
				(hide yes)
			)
		)
		(property "Datasheet" ""
			(at 317.5 88.9 0)
			(effects
				(font
					(size 1.27 1.27)
					(thickness 0.15)
				)
				(justify left bottom)
				(hide yes)
			)
		)
		(property "Description" ""
			(at 308.61 76.2 0)
			(effects
				(font
					(size 1.27 1.27)
				)
				(hide yes)
			)
		)
		(property "Author" "Antmicro"
			(at 317.5 83.82 0)
			(effects
				(font
					(size 1.27 1.27)
					(thickness 0.15)
				)
				(justify left bottom)
				(hide yes)
			)
		)
		(property "License" "Apache-2.0"
			(at 317.5 86.36 0)
			(effects
				(font
					(size 1.27 1.27)
					(thickness 0.15)
				)
				(justify left bottom)
				(hide yes)
			)
		)
		(pin "1"
		)
		(instances
			(project "OCuLink to 10GbE adapter"
				(path ""
					(reference "#PWR0140")
					(unit 1)
				)
			)
		)
	)
	(symbol
		(lib_id "antmicroFerriteBeadsandChips:FB_33Z_3A_Murata-BLM18PG_0603")
		(at 45.72 119.38 0)
		(unit 1)
		(exclude_from_sim no)
		(in_bom yes)
		(on_board yes)
		(dnp no)
		(fields_autoplaced yes)
		(property "Reference" "FB4"
			(at 48.2219 113.03 0)
			(effects
				(font
					(size 1.27 1.27)
					(thickness 0.15)
				)
			)
		)
		(property "Value" "FB_33Z_3A_Murata-BLM18PG_0603"
			(at 59.69 121.92 0)
			(effects
				(font
					(size 1.27 1.27)
					(thickness 0.15)
				)
				(justify left bottom)
				(hide yes)
			)
		)
		(property "Footprint" "antmicro-footprints:FB_0603_1608Metric"
			(at 59.69 127 0)
			(effects
				(font
					(size 1.27 1.27)
					(thickness 0.15)
				)
				(justify left bottom)
				(hide yes)
			)
		)
		(property "Datasheet" "https://www.murata.com/products/productdata/8796737273886/QNFA9101.pdf?1649080818000"
			(at 59.69 129.54 0)
			(effects
				(font
					(size 1.27 1.27)
					(thickness 0.15)
				)
				(justify left bottom)
				(hide yes)
			)
		)
		(property "Description" "Ferrite Bead, 0603 [1608 Metric], 33 ohm, 3 A, BLM18PG, 0.025 ohm, ± 25%, DC power line"
			(at 45.72 119.38 0)
			(effects
				(font
					(size 1.27 1.27)
				)
				(hide yes)
			)
		)
		(property "Val" "33Z/3A"
			(at 48.2219 115.57 0)
			(effects
				(font
					(size 1.27 1.27)
				)
			)
		)
		(property "MPN" "BLM18PG330SH1D"
			(at 59.69 132.08 0)
			(effects
				(font
					(size 1.27 1.27)
					(thickness 0.15)
				)
				(justify left bottom)
				(hide yes)
			)
		)
		(property "Manufacturer" "Murata"
			(at 59.69 134.62 0)
			(effects
				(font
					(size 1.27 1.27)
					(thickness 0.15)
				)
				(justify left bottom)
				(hide yes)
			)
		)
		(property "Current" ""
			(at 66.04 142.24 0)
			(effects
				(font
					(size 1.27 1.27)
					(thickness 0.15)
				)
				(justify left bottom)
				(hide yes)
			)
		)
		(property "Author" "Antmicro"
			(at 59.69 137.16 0)
			(effects
				(font
					(size 1.27 1.27)
					(thickness 0.15)
				)
				(justify left bottom)
				(hide yes)
			)
		)
		(property "License" "Apache-2.0"
			(at 59.69 139.7 0)
			(effects
				(font
					(size 1.27 1.27)
					(thickness 0.15)
				)
				(justify left bottom)
				(hide yes)
			)
		)
		(pin "2"
		)
		(pin "1"
		)
		(instances
			(project "OCuLink to 10GbE adapter"
				(path ""
					(reference "FB4")
					(unit 1)
				)
			)
		)
	)
	(symbol
		(lib_id "antmicroCapacitors0402:C_1u_25V_0402")
		(at 361.95 52.07 90)
		(unit 1)
		(exclude_from_sim no)
		(in_bom yes)
		(on_board yes)
		(dnp no)
		(property "Reference" "C94"
			(at 363.982 48.26 90)
			(effects
				(font
					(size 1.27 1.27)
					(thickness 0.15)
				)
				(justify right)
			)
		)
		(property "Value" "C_1u_25V_0402"
			(at 372.11 31.75 0)
			(effects
				(font
					(size 1.27 1.27)
					(thickness 0.15)
				)
				(justify left bottom)
				(hide yes)
			)
		)
		(property "Footprint" "antmicro-footprints:C_0402_1005Metric"
			(at 374.65 31.75 0)
			(effects
				(font
					(size 1.27 1.27)
					(thickness 0.15)
				)
				(justify left bottom)
				(hide yes)
			)
		)
		(property "Datasheet" "https://www.murata.com/products/productdetail?partno=GRM155R61E105KE11%23"
			(at 377.19 31.75 0)
			(effects
				(font
					(size 1.27 1.27)
					(thickness 0.15)
				)
				(justify left bottom)
				(hide yes)
			)
		)
		(property "Description" "SMD Multilayer Ceramic Capacitor, 1 µF, 25 V, 0402 [1005 Metric], ± 10%, X5R, GRM Series"
			(at 361.95 52.07 0)
			(effects
				(font
					(size 1.27 1.27)
				)
				(hide yes)
			)
		)
		(property "MPN" "GRM155R61E105KE11J"
			(at 379.73 31.75 0)
			(effects
				(font
					(size 1.27 1.27)
					(thickness 0.15)
				)
				(justify left bottom)
				(hide yes)
			)
		)
		(property "Manufacturer" "Murata"
			(at 382.27 31.75 0)
			(effects
				(font
					(size 1.27 1.27)
					(thickness 0.15)
				)
				(justify left bottom)
				(hide yes)
			)
		)
		(property "License" "Apache-2.0"
			(at 384.81 31.75 0)
			(effects
				(font
					(size 1.27 1.27)
					(thickness 0.15)
				)
				(justify left bottom)
				(hide yes)
			)
		)
		(property "Author" "Antmicro"
			(at 387.35 31.75 0)
			(effects
				(font
					(size 1.27 1.27)
					(thickness 0.15)
				)
				(justify left bottom)
				(hide yes)
			)
		)
		(property "Val" "1u"
			(at 363.982 50.8 90)
			(effects
				(font
					(size 1.27 1.27)
					(thickness 0.15)
				)
				(justify right)
			)
		)
		(property "Voltage" "25V"
			(at 389.89 31.75 0)
			(effects
				(font
					(size 1.27 1.27)
				)
				(justify left bottom)
				(hide yes)
			)
		)
		(property "Dielectric" "X5R"
			(at 392.43 31.75 0)
			(effects
				(font
					(size 1.27 1.27)
				)
				(justify left bottom)
				(hide yes)
			)
		)
		(pin "2"
		)
		(pin "1"
		)
		(instances
			(project "OCuLink to 10GbE adapter"
				(path ""
					(reference "C94")
					(unit 1)
				)
			)
		)
	)
	(symbol
		(lib_id "antmicropower:GND")
		(at 317.5 93.98 0)
		(unit 1)
		(exclude_from_sim no)
		(in_bom yes)
		(on_board yes)
		(dnp no)
		(property "Reference" "#PWR0166"
			(at 326.39 96.52 0)
			(effects
				(font
					(size 1.27 1.27)
					(thickness 0.15)
				)
				(justify left bottom)
				(hide yes)
			)
		)
		(property "Value" "GND"
			(at 317.5 97.79 0)
			(effects
				(font
					(size 1.27 1.27)
					(thickness 0.15)
				)
			)
		)
		(property "Footprint" ""
			(at 326.39 101.6 0)
			(effects
				(font
					(size 1.27 1.27)
					(thickness 0.15)
				)
				(justify left bottom)
				(hide yes)
			)
		)
		(property "Datasheet" ""
			(at 326.39 106.68 0)
			(effects
				(font
					(size 1.27 1.27)
					(thickness 0.15)
				)
				(justify left bottom)
				(hide yes)
			)
		)
		(property "Description" ""
			(at 317.5 93.98 0)
			(effects
				(font
					(size 1.27 1.27)
				)
				(hide yes)
			)
		)
		(property "Author" "Antmicro"
			(at 326.39 101.6 0)
			(effects
				(font
					(size 1.27 1.27)
					(thickness 0.15)
				)
				(justify left bottom)
				(hide yes)
			)
		)
		(property "License" "Apache-2.0"
			(at 326.39 104.14 0)
			(effects
				(font
					(size 1.27 1.27)
					(thickness 0.15)
				)
				(justify left bottom)
				(hide yes)
			)
		)
		(pin "1"
		)
		(instances
			(project "OCuLink to 10GbE adapter"
				(path ""
					(reference "#PWR0166")
					(unit 1)
				)
			)
		)
	)
	(symbol
		(lib_id "antmicroCapacitors0402:C_1u_25V_0402")
		(at 308.61 91.44 90)
		(unit 1)
		(exclude_from_sim no)
		(in_bom yes)
		(on_board yes)
		(dnp no)
		(property "Reference" "C118"
			(at 310.642 87.63 90)
			(effects
				(font
					(size 1.27 1.27)
					(thickness 0.15)
				)
				(justify right)
			)
		)
		(property "Value" "C_1u_25V_0402"
			(at 318.77 71.12 0)
			(effects
				(font
					(size 1.27 1.27)
					(thickness 0.15)
				)
				(justify left bottom)
				(hide yes)
			)
		)
		(property "Footprint" "antmicro-footprints:C_0402_1005Metric"
			(at 321.31 71.12 0)
			(effects
				(font
					(size 1.27 1.27)
					(thickness 0.15)
				)
				(justify left bottom)
				(hide yes)
			)
		)
		(property "Datasheet" "https://www.murata.com/products/productdetail?partno=GRM155R61E105KE11%23"
			(at 323.85 71.12 0)
			(effects
				(font
					(size 1.27 1.27)
					(thickness 0.15)
				)
				(justify left bottom)
				(hide yes)
			)
		)
		(property "Description" "SMD Multilayer Ceramic Capacitor, 1 µF, 25 V, 0402 [1005 Metric], ± 10%, X5R, GRM Series"
			(at 308.61 91.44 0)
			(effects
				(font
					(size 1.27 1.27)
				)
				(hide yes)
			)
		)
		(property "MPN" "GRM155R61E105KE11J"
			(at 326.39 71.12 0)
			(effects
				(font
					(size 1.27 1.27)
					(thickness 0.15)
				)
				(justify left bottom)
				(hide yes)
			)
		)
		(property "Manufacturer" "Murata"
			(at 328.93 71.12 0)
			(effects
				(font
					(size 1.27 1.27)
					(thickness 0.15)
				)
				(justify left bottom)
				(hide yes)
			)
		)
		(property "License" "Apache-2.0"
			(at 331.47 71.12 0)
			(effects
				(font
					(size 1.27 1.27)
					(thickness 0.15)
				)
				(justify left bottom)
				(hide yes)
			)
		)
		(property "Author" "Antmicro"
			(at 334.01 71.12 0)
			(effects
				(font
					(size 1.27 1.27)
					(thickness 0.15)
				)
				(justify left bottom)
				(hide yes)
			)
		)
		(property "Val" "1u"
			(at 310.642 90.17 90)
			(effects
				(font
					(size 1.27 1.27)
					(thickness 0.15)
				)
				(justify right)
			)
		)
		(property "Voltage" "25V"
			(at 336.55 71.12 0)
			(effects
				(font
					(size 1.27 1.27)
				)
				(justify left bottom)
				(hide yes)
			)
		)
		(property "Dielectric" "X5R"
			(at 339.09 71.12 0)
			(effects
				(font
					(size 1.27 1.27)
				)
				(justify left bottom)
				(hide yes)
			)
		)
		(pin "2"
		)
		(pin "1"
		)
		(instances
			(project "OCuLink to 10GbE adapter"
				(path ""
					(reference "C118")
					(unit 1)
				)
			)
		)
	)
	(symbol
		(lib_id "antmicropower:GND")
		(at 88.9 182.88 0)
		(unit 1)
		(exclude_from_sim no)
		(in_bom yes)
		(on_board yes)
		(dnp no)
		(property "Reference" "#PWR0227"
			(at 97.79 185.42 0)
			(effects
				(font
					(size 1.27 1.27)
					(thickness 0.15)
				)
				(justify left bottom)
				(hide yes)
			)
		)
		(property "Value" "GND"
			(at 88.9 186.69 0)
			(effects
				(font
					(size 1.27 1.27)
					(thickness 0.15)
				)
			)
		)
		(property "Footprint" ""
			(at 97.79 190.5 0)
			(effects
				(font
					(size 1.27 1.27)
					(thickness 0.15)
				)
				(justify left bottom)
				(hide yes)
			)
		)
		(property "Datasheet" ""
			(at 97.79 195.58 0)
			(effects
				(font
					(size 1.27 1.27)
					(thickness 0.15)
				)
				(justify left bottom)
				(hide yes)
			)
		)
		(property "Description" ""
			(at 88.9 182.88 0)
			(effects
				(font
					(size 1.27 1.27)
				)
				(hide yes)
			)
		)
		(property "Author" "Antmicro"
			(at 97.79 190.5 0)
			(effects
				(font
					(size 1.27 1.27)
					(thickness 0.15)
				)
				(justify left bottom)
				(hide yes)
			)
		)
		(property "License" "Apache-2.0"
			(at 97.79 193.04 0)
			(effects
				(font
					(size 1.27 1.27)
					(thickness 0.15)
				)
				(justify left bottom)
				(hide yes)
			)
		)
		(pin "1"
		)
		(instances
			(project "OCuLink to 10GbE adapter"
				(path ""
					(reference "#PWR0227")
					(unit 1)
				)
			)
		)
	)
	(symbol
		(lib_id "antmicroCapacitors0402:C_1u_25V_0402")
		(at 370.84 52.07 90)
		(unit 1)
		(exclude_from_sim no)
		(in_bom yes)
		(on_board yes)
		(dnp no)
		(property "Reference" "C95"
			(at 372.872 48.26 90)
			(effects
				(font
					(size 1.27 1.27)
					(thickness 0.15)
				)
				(justify right)
			)
		)
		(property "Value" "C_1u_25V_0402"
			(at 381 31.75 0)
			(effects
				(font
					(size 1.27 1.27)
					(thickness 0.15)
				)
				(justify left bottom)
				(hide yes)
			)
		)
		(property "Footprint" "antmicro-footprints:C_0402_1005Metric"
			(at 383.54 31.75 0)
			(effects
				(font
					(size 1.27 1.27)
					(thickness 0.15)
				)
				(justify left bottom)
				(hide yes)
			)
		)
		(property "Datasheet" "https://www.murata.com/products/productdetail?partno=GRM155R61E105KE11%23"
			(at 386.08 31.75 0)
			(effects
				(font
					(size 1.27 1.27)
					(thickness 0.15)
				)
				(justify left bottom)
				(hide yes)
			)
		)
		(property "Description" "SMD Multilayer Ceramic Capacitor, 1 µF, 25 V, 0402 [1005 Metric], ± 10%, X5R, GRM Series"
			(at 370.84 52.07 0)
			(effects
				(font
					(size 1.27 1.27)
				)
				(hide yes)
			)
		)
		(property "MPN" "GRM155R61E105KE11J"
			(at 388.62 31.75 0)
			(effects
				(font
					(size 1.27 1.27)
					(thickness 0.15)
				)
				(justify left bottom)
				(hide yes)
			)
		)
		(property "Manufacturer" "Murata"
			(at 391.16 31.75 0)
			(effects
				(font
					(size 1.27 1.27)
					(thickness 0.15)
				)
				(justify left bottom)
				(hide yes)
			)
		)
		(property "License" "Apache-2.0"
			(at 393.7 31.75 0)
			(effects
				(font
					(size 1.27 1.27)
					(thickness 0.15)
				)
				(justify left bottom)
				(hide yes)
			)
		)
		(property "Author" "Antmicro"
			(at 396.24 31.75 0)
			(effects
				(font
					(size 1.27 1.27)
					(thickness 0.15)
				)
				(justify left bottom)
				(hide yes)
			)
		)
		(property "Val" "1u"
			(at 372.872 50.8 90)
			(effects
				(font
					(size 1.27 1.27)
					(thickness 0.15)
				)
				(justify right)
			)
		)
		(property "Voltage" "25V"
			(at 398.78 31.75 0)
			(effects
				(font
					(size 1.27 1.27)
				)
				(justify left bottom)
				(hide yes)
			)
		)
		(property "Dielectric" "X5R"
			(at 401.32 31.75 0)
			(effects
				(font
					(size 1.27 1.27)
				)
				(justify left bottom)
				(hide yes)
			)
		)
		(pin "2"
		)
		(pin "1"
		)
		(instances
			(project "OCuLink to 10GbE adapter"
				(path ""
					(reference "C95")
					(unit 1)
				)
			)
		)
	)
	(symbol
		(lib_id "antmicropower:GND")
		(at 106.68 156.21 0)
		(unit 1)
		(exclude_from_sim no)
		(in_bom yes)
		(on_board yes)
		(dnp no)
		(property "Reference" "#PWR0219"
			(at 115.57 158.75 0)
			(effects
				(font
					(size 1.27 1.27)
					(thickness 0.15)
				)
				(justify left bottom)
				(hide yes)
			)
		)
		(property "Value" "GND"
			(at 106.68 160.02 0)
			(effects
				(font
					(size 1.27 1.27)
					(thickness 0.15)
				)
			)
		)
		(property "Footprint" ""
			(at 115.57 163.83 0)
			(effects
				(font
					(size 1.27 1.27)
					(thickness 0.15)
				)
				(justify left bottom)
				(hide yes)
			)
		)
		(property "Datasheet" ""
			(at 115.57 168.91 0)
			(effects
				(font
					(size 1.27 1.27)
					(thickness 0.15)
				)
				(justify left bottom)
				(hide yes)
			)
		)
		(property "Description" ""
			(at 106.68 156.21 0)
			(effects
				(font
					(size 1.27 1.27)
				)
				(hide yes)
			)
		)
		(property "Author" "Antmicro"
			(at 115.57 163.83 0)
			(effects
				(font
					(size 1.27 1.27)
					(thickness 0.15)
				)
				(justify left bottom)
				(hide yes)
			)
		)
		(property "License" "Apache-2.0"
			(at 115.57 166.37 0)
			(effects
				(font
					(size 1.27 1.27)
					(thickness 0.15)
				)
				(justify left bottom)
				(hide yes)
			)
		)
		(pin "1"
		)
		(instances
			(project "OCuLink to 10GbE adapter"
				(path ""
					(reference "#PWR0219")
					(unit 1)
				)
			)
		)
	)
	(symbol
		(lib_id "antmicropower:+1V0")
		(at 21.59 170.18 0)
		(unit 1)
		(exclude_from_sim no)
		(in_bom yes)
		(on_board yes)
		(dnp no)
		(property "Reference" "#PWR0221"
			(at 21.59 173.99 0)
			(effects
				(font
					(size 1.27 1.27)
				)
				(hide yes)
			)
		)
		(property "Value" "+1V0"
			(at 21.59 166.116 0)
			(effects
				(font
					(size 1.27 1.27)
				)
			)
		)
		(property "Footprint" ""
			(at 21.59 170.18 0)
			(effects
				(font
					(size 1.27 1.27)
				)
				(hide yes)
			)
		)
		(property "Datasheet" ""
			(at 21.59 170.18 0)
			(effects
				(font
					(size 1.27 1.27)
				)
				(hide yes)
			)
		)
		(property "Description" ""
			(at 21.59 170.18 0)
			(effects
				(font
					(size 1.27 1.27)
				)
				(hide yes)
			)
		)
		(pin "1"
		)
		(instances
			(project "OCuLink to 10GbE adapter"
				(path ""
					(reference "#PWR0221")
					(unit 1)
				)
			)
		)
	)
	(symbol
		(lib_id "antmicropower:GND")
		(at 317.5 133.35 0)
		(unit 1)
		(exclude_from_sim no)
		(in_bom yes)
		(on_board yes)
		(dnp no)
		(property "Reference" "#PWR0197"
			(at 326.39 135.89 0)
			(effects
				(font
					(size 1.27 1.27)
					(thickness 0.15)
				)
				(justify left bottom)
				(hide yes)
			)
		)
		(property "Value" "GND"
			(at 317.5 137.16 0)
			(effects
				(font
					(size 1.27 1.27)
					(thickness 0.15)
				)
			)
		)
		(property "Footprint" ""
			(at 326.39 140.97 0)
			(effects
				(font
					(size 1.27 1.27)
					(thickness 0.15)
				)
				(justify left bottom)
				(hide yes)
			)
		)
		(property "Datasheet" ""
			(at 326.39 146.05 0)
			(effects
				(font
					(size 1.27 1.27)
					(thickness 0.15)
				)
				(justify left bottom)
				(hide yes)
			)
		)
		(property "Description" ""
			(at 317.5 133.35 0)
			(effects
				(font
					(size 1.27 1.27)
				)
				(hide yes)
			)
		)
		(property "Author" "Antmicro"
			(at 326.39 140.97 0)
			(effects
				(font
					(size 1.27 1.27)
					(thickness 0.15)
				)
				(justify left bottom)
				(hide yes)
			)
		)
		(property "License" "Apache-2.0"
			(at 326.39 143.51 0)
			(effects
				(font
					(size 1.27 1.27)
					(thickness 0.15)
				)
				(justify left bottom)
				(hide yes)
			)
		)
		(pin "1"
		)
		(instances
			(project "OCuLink to 10GbE adapter"
				(path ""
					(reference "#PWR0197")
					(unit 1)
				)
			)
		)
	)
	(symbol
		(lib_id "antmicroCapacitors0402:C_1u_25V_0402")
		(at 97.79 73.66 90)
		(unit 1)
		(exclude_from_sim no)
		(in_bom yes)
		(on_board yes)
		(dnp no)
		(property "Reference" "C102"
			(at 99.822 69.85 90)
			(effects
				(font
					(size 1.27 1.27)
					(thickness 0.15)
				)
				(justify right)
			)
		)
		(property "Value" "C_1u_25V_0402"
			(at 107.95 53.34 0)
			(effects
				(font
					(size 1.27 1.27)
					(thickness 0.15)
				)
				(justify left bottom)
				(hide yes)
			)
		)
		(property "Footprint" "antmicro-footprints:C_0402_1005Metric"
			(at 110.49 53.34 0)
			(effects
				(font
					(size 1.27 1.27)
					(thickness 0.15)
				)
				(justify left bottom)
				(hide yes)
			)
		)
		(property "Datasheet" "https://www.murata.com/products/productdetail?partno=GRM155R61E105KE11%23"
			(at 113.03 53.34 0)
			(effects
				(font
					(size 1.27 1.27)
					(thickness 0.15)
				)
				(justify left bottom)
				(hide yes)
			)
		)
		(property "Description" "SMD Multilayer Ceramic Capacitor, 1 µF, 25 V, 0402 [1005 Metric], ± 10%, X5R, GRM Series"
			(at 97.79 73.66 0)
			(effects
				(font
					(size 1.27 1.27)
				)
				(hide yes)
			)
		)
		(property "MPN" "GRM155R61E105KE11J"
			(at 115.57 53.34 0)
			(effects
				(font
					(size 1.27 1.27)
					(thickness 0.15)
				)
				(justify left bottom)
				(hide yes)
			)
		)
		(property "Manufacturer" "Murata"
			(at 118.11 53.34 0)
			(effects
				(font
					(size 1.27 1.27)
					(thickness 0.15)
				)
				(justify left bottom)
				(hide yes)
			)
		)
		(property "License" "Apache-2.0"
			(at 120.65 53.34 0)
			(effects
				(font
					(size 1.27 1.27)
					(thickness 0.15)
				)
				(justify left bottom)
				(hide yes)
			)
		)
		(property "Author" "Antmicro"
			(at 123.19 53.34 0)
			(effects
				(font
					(size 1.27 1.27)
					(thickness 0.15)
				)
				(justify left bottom)
				(hide yes)
			)
		)
		(property "Val" "1u"
			(at 99.822 72.39 90)
			(effects
				(font
					(size 1.27 1.27)
					(thickness 0.15)
				)
				(justify right)
			)
		)
		(property "Voltage" "25V"
			(at 125.73 53.34 0)
			(effects
				(font
					(size 1.27 1.27)
				)
				(justify left bottom)
				(hide yes)
			)
		)
		(property "Dielectric" "X5R"
			(at 128.27 53.34 0)
			(effects
				(font
					(size 1.27 1.27)
				)
				(justify left bottom)
				(hide yes)
			)
		)
		(pin "2"
		)
		(pin "1"
		)
		(instances
			(project "OCuLink to 10GbE adapter"
				(path ""
					(reference "C102")
					(unit 1)
				)
			)
		)
	)
	(symbol
		(lib_id "antmicropower:GND")
		(at 39.37 262.89 0)
		(unit 1)
		(exclude_from_sim no)
		(in_bom yes)
		(on_board yes)
		(dnp no)
		(property "Reference" "#PWR0243"
			(at 48.26 265.43 0)
			(effects
				(font
					(size 1.27 1.27)
					(thickness 0.15)
				)
				(justify left bottom)
				(hide yes)
			)
		)
		(property "Value" "GND"
			(at 39.37 266.7 0)
			(effects
				(font
					(size 1.27 1.27)
					(thickness 0.15)
				)
			)
		)
		(property "Footprint" ""
			(at 48.26 270.51 0)
			(effects
				(font
					(size 1.27 1.27)
					(thickness 0.15)
				)
				(justify left bottom)
				(hide yes)
			)
		)
		(property "Datasheet" ""
			(at 48.26 275.59 0)
			(effects
				(font
					(size 1.27 1.27)
					(thickness 0.15)
				)
				(justify left bottom)
				(hide yes)
			)
		)
		(property "Description" ""
			(at 39.37 262.89 0)
			(effects
				(font
					(size 1.27 1.27)
				)
				(hide yes)
			)
		)
		(property "Author" "Antmicro"
			(at 48.26 270.51 0)
			(effects
				(font
					(size 1.27 1.27)
					(thickness 0.15)
				)
				(justify left bottom)
				(hide yes)
			)
		)
		(property "License" "Apache-2.0"
			(at 48.26 273.05 0)
			(effects
				(font
					(size 1.27 1.27)
					(thickness 0.15)
				)
				(justify left bottom)
				(hide yes)
			)
		)
		(pin "1"
		)
		(instances
			(project "OCuLink to 10GbE adapter"
				(path ""
					(reference "#PWR0243")
					(unit 1)
				)
			)
		)
	)
	(symbol
		(lib_id "antmicropower:+1V0")
		(at 21.59 223.52 0)
		(unit 1)
		(exclude_from_sim no)
		(in_bom yes)
		(on_board yes)
		(dnp no)
		(property "Reference" "#PWR0238"
			(at 21.59 227.33 0)
			(effects
				(font
					(size 1.27 1.27)
				)
				(hide yes)
			)
		)
		(property "Value" "+1V0"
			(at 21.59 219.456 0)
			(effects
				(font
					(size 1.27 1.27)
				)
			)
		)
		(property "Footprint" ""
			(at 21.59 223.52 0)
			(effects
				(font
					(size 1.27 1.27)
				)
				(hide yes)
			)
		)
		(property "Datasheet" ""
			(at 21.59 223.52 0)
			(effects
				(font
					(size 1.27 1.27)
				)
				(hide yes)
			)
		)
		(property "Description" ""
			(at 21.59 223.52 0)
			(effects
				(font
					(size 1.27 1.27)
				)
				(hide yes)
			)
		)
		(pin "1"
		)
		(instances
			(project "OCuLink to 10GbE adapter"
				(path ""
					(reference "#PWR0238")
					(unit 1)
				)
			)
		)
	)
	(symbol
		(lib_id "antmicropower:GND")
		(at 31.75 182.88 0)
		(unit 1)
		(exclude_from_sim no)
		(in_bom yes)
		(on_board yes)
		(dnp no)
		(property "Reference" "#PWR0222"
			(at 40.64 185.42 0)
			(effects
				(font
					(size 1.27 1.27)
					(thickness 0.15)
				)
				(justify left bottom)
				(hide yes)
			)
		)
		(property "Value" "GND"
			(at 31.75 186.69 0)
			(effects
				(font
					(size 1.27 1.27)
					(thickness 0.15)
				)
			)
		)
		(property "Footprint" ""
			(at 40.64 190.5 0)
			(effects
				(font
					(size 1.27 1.27)
					(thickness 0.15)
				)
				(justify left bottom)
				(hide yes)
			)
		)
		(property "Datasheet" ""
			(at 40.64 195.58 0)
			(effects
				(font
					(size 1.27 1.27)
					(thickness 0.15)
				)
				(justify left bottom)
				(hide yes)
			)
		)
		(property "Description" ""
			(at 31.75 182.88 0)
			(effects
				(font
					(size 1.27 1.27)
				)
				(hide yes)
			)
		)
		(property "Author" "Antmicro"
			(at 40.64 190.5 0)
			(effects
				(font
					(size 1.27 1.27)
					(thickness 0.15)
				)
				(justify left bottom)
				(hide yes)
			)
		)
		(property "License" "Apache-2.0"
			(at 40.64 193.04 0)
			(effects
				(font
					(size 1.27 1.27)
					(thickness 0.15)
				)
				(justify left bottom)
				(hide yes)
			)
		)
		(pin "1"
		)
		(instances
			(project "OCuLink to 10GbE adapter"
				(path ""
					(reference "#PWR0222")
					(unit 1)
				)
			)
		)
	)
	(symbol
		(lib_id "antmicroCapacitors0603:C_22u_16V_0603")
		(at 379.73 91.44 90)
		(unit 1)
		(exclude_from_sim no)
		(in_bom yes)
		(on_board yes)
		(dnp no)
		(fields_autoplaced yes)
		(property "Reference" "C125"
			(at 382.27 87.6236 90)
			(effects
				(font
					(size 1.27 1.27)
					(thickness 0.15)
				)
				(justify right)
			)
		)
		(property "Value" "C_22u_16V_0603"
			(at 389.89 71.12 0)
			(effects
				(font
					(size 1.27 1.27)
					(thickness 0.15)
				)
				(justify left bottom)
				(hide yes)
			)
		)
		(property "Footprint" "antmicro-footprints:C_0603_1608Metric_EIA"
			(at 392.43 71.12 0)
			(effects
				(font
					(size 1.27 1.27)
					(thickness 0.15)
				)
				(justify left bottom)
				(hide yes)
			)
		)
		(property "Datasheet" "https://product.samsungsem.com/mlcc/CL10A226MO7JZN.do"
			(at 394.97 71.12 0)
			(effects
				(font
					(size 1.27 1.27)
					(thickness 0.15)
				)
				(justify left bottom)
				(hide yes)
			)
		)
		(property "Description" "SMD Multilayer Ceramic Capacitor"
			(at 379.73 91.44 0)
			(effects
				(font
					(size 1.27 1.27)
				)
				(hide yes)
			)
		)
		(property "MPN" "CL10A226MO7JZNC"
			(at 397.51 71.12 0)
			(effects
				(font
					(size 1.27 1.27)
					(thickness 0.15)
				)
				(justify left bottom)
				(hide yes)
			)
		)
		(property "Manufacturer" "Samsung Electro-Mechanics"
			(at 400.05 71.12 0)
			(effects
				(font
					(size 1.27 1.27)
					(thickness 0.15)
				)
				(justify left bottom)
				(hide yes)
			)
		)
		(property "License" "Apache-2.0"
			(at 402.59 71.12 0)
			(effects
				(font
					(size 1.27 1.27)
					(thickness 0.15)
				)
				(justify left bottom)
				(hide yes)
			)
		)
		(property "Author" "Antmicro"
			(at 405.13 71.12 0)
			(effects
				(font
					(size 1.27 1.27)
					(thickness 0.15)
				)
				(justify left bottom)
				(hide yes)
			)
		)
		(property "Val" "22u"
			(at 382.27 90.1636 90)
			(effects
				(font
					(size 1.27 1.27)
					(thickness 0.15)
				)
				(justify right)
			)
		)
		(property "Voltage" "16V"
			(at 407.67 71.12 0)
			(effects
				(font
					(size 1.27 1.27)
				)
				(justify left bottom)
				(hide yes)
			)
		)
		(property "Dielectric" ""
			(at 410.21 71.12 0)
			(effects
				(font
					(size 1.27 1.27)
				)
				(justify left bottom)
				(hide yes)
			)
		)
		(pin "1"
		)
		(pin "2"
		)
		(instances
			(project "OCuLink to 10GbE adapter"
				(path ""
					(reference "C125")
					(unit 1)
				)
			)
		)
	)
	(symbol
		(lib_id "antmicroCapacitors0603:C_10u_10V_X7R_0603")
		(at 292.1 149.86 270)
		(mirror x)
		(unit 1)
		(exclude_from_sim no)
		(in_bom yes)
		(on_board yes)
		(dnp no)
		(property "Reference" "C158"
			(at 290.068 146.05 90)
			(effects
				(font
					(size 1.27 1.27)
					(thickness 0.15)
				)
				(justify right)
			)
		)
		(property "Value" "C_10u_10V_X7R_0603"
			(at 281.94 134.62 0)
			(effects
				(font
					(size 1.27 1.27)
					(thickness 0.15)
				)
				(justify left bottom)
				(hide yes)
			)
		)
		(property "Footprint" "antmicro-footprints:C_0603_1608Metric"
			(at 279.4 134.62 0)
			(effects
				(font
					(size 1.27 1.27)
					(thickness 0.15)
				)
				(justify left bottom)
				(hide yes)
			)
		)
		(property "Datasheet" "https://www.murata.com/products/productdetail?partno=GRM188Z71A106KA73%23"
			(at 276.86 134.62 0)
			(effects
				(font
					(size 1.27 1.27)
					(thickness 0.15)
				)
				(justify left bottom)
				(hide yes)
			)
		)
		(property "Description" "SMD Multilayer Ceramic Capacitor,  10µF, 10V, 0603, ±10%, X7R"
			(at 292.1 149.86 0)
			(effects
				(font
					(size 1.27 1.27)
				)
				(hide yes)
			)
		)
		(property "MPN" "GRM188Z71A106KA73D"
			(at 274.32 134.62 0)
			(effects
				(font
					(size 1.27 1.27)
					(thickness 0.15)
				)
				(justify left bottom)
				(hide yes)
			)
		)
		(property "Val" "10u"
			(at 290.068 148.59 90)
			(effects
				(font
					(size 1.27 1.27)
					(thickness 0.15)
				)
				(justify right)
			)
		)
		(property "Voltage" "10V"
			(at 271.78 134.62 0)
			(effects
				(font
					(size 1.27 1.27)
					(thickness 0.15)
				)
				(justify left bottom)
				(hide yes)
			)
		)
		(property "Dielectric" "X7R"
			(at 269.24 134.62 0)
			(effects
				(font
					(size 1.27 1.27)
					(thickness 0.15)
				)
				(justify left bottom)
				(hide yes)
			)
		)
		(property "Manufacturer" "Murata"
			(at 266.7 134.62 0)
			(effects
				(font
					(size 1.27 1.27)
					(thickness 0.15)
				)
				(justify left bottom)
				(hide yes)
			)
		)
		(property "License" "Apache-2.0"
			(at 264.16 134.62 0)
			(effects
				(font
					(size 1.27 1.27)
					(thickness 0.15)
				)
				(justify left bottom)
				(hide yes)
			)
		)
		(property "Author" "Antmicro"
			(at 261.62 134.62 0)
			(effects
				(font
					(size 1.27 1.27)
					(thickness 0.15)
				)
				(justify left bottom)
				(hide yes)
			)
		)
		(pin "1"
		)
		(pin "2"
		)
		(instances
			(project "OCuLink to 10GbE adapter"
				(path ""
					(reference "C158")
					(unit 1)
				)
			)
		)
	)
	(symbol
		(lib_id "antmicropower:GND")
		(at 53.34 129.54 0)
		(unit 1)
		(exclude_from_sim no)
		(in_bom yes)
		(on_board yes)
		(dnp no)
		(property "Reference" "#PWR0188"
			(at 62.23 132.08 0)
			(effects
				(font
					(size 1.27 1.27)
					(thickness 0.15)
				)
				(justify left bottom)
				(hide yes)
			)
		)
		(property "Value" "GND"
			(at 53.34 133.35 0)
			(effects
				(font
					(size 1.27 1.27)
					(thickness 0.15)
				)
			)
		)
		(property "Footprint" ""
			(at 62.23 137.16 0)
			(effects
				(font
					(size 1.27 1.27)
					(thickness 0.15)
				)
				(justify left bottom)
				(hide yes)
			)
		)
		(property "Datasheet" ""
			(at 62.23 142.24 0)
			(effects
				(font
					(size 1.27 1.27)
					(thickness 0.15)
				)
				(justify left bottom)
				(hide yes)
			)
		)
		(property "Description" ""
			(at 53.34 129.54 0)
			(effects
				(font
					(size 1.27 1.27)
				)
				(hide yes)
			)
		)
		(property "Author" "Antmicro"
			(at 62.23 137.16 0)
			(effects
				(font
					(size 1.27 1.27)
					(thickness 0.15)
				)
				(justify left bottom)
				(hide yes)
			)
		)
		(property "License" "Apache-2.0"
			(at 62.23 139.7 0)
			(effects
				(font
					(size 1.27 1.27)
					(thickness 0.15)
				)
				(justify left bottom)
				(hide yes)
			)
		)
		(pin "1"
		)
		(instances
			(project "OCuLink to 10GbE adapter"
				(path ""
					(reference "#PWR0188")
					(unit 1)
				)
			)
		)
	)
	(symbol
		(lib_id "antmicropower:VDD")
		(at 196.85 78.74 0)
		(unit 1)
		(exclude_from_sim no)
		(in_bom yes)
		(on_board yes)
		(dnp no)
		(property "Reference" "#PWR0157"
			(at 196.85 82.55 0)
			(effects
				(font
					(size 1.27 1.27)
				)
				(hide yes)
			)
		)
		(property "Value" "XGB_AVDDH"
			(at 196.85 74.93 0)
			(effects
				(font
					(size 1.27 1.27)
				)
			)
		)
		(property "Footprint" ""
			(at 196.85 78.74 0)
			(effects
				(font
					(size 1.27 1.27)
				)
				(hide yes)
			)
		)
		(property "Datasheet" ""
			(at 196.85 78.74 0)
			(effects
				(font
					(size 1.27 1.27)
				)
				(hide yes)
			)
		)
		(property "Description" ""
			(at 196.85 78.74 0)
			(effects
				(font
					(size 1.27 1.27)
				)
				(hide yes)
			)
		)
		(pin "1"
		)
		(instances
			(project "OCuLink to 10GbE adapter"
				(path ""
					(reference "#PWR0157")
					(unit 1)
				)
			)
		)
	)
	(symbol
		(lib_id "antmicropower:VDD")
		(at 214.63 78.74 0)
		(unit 1)
		(exclude_from_sim no)
		(in_bom yes)
		(on_board yes)
		(dnp no)
		(property "Reference" "#PWR0159"
			(at 214.63 82.55 0)
			(effects
				(font
					(size 1.27 1.27)
				)
				(hide yes)
			)
		)
		(property "Value" "DVDD"
			(at 214.63 74.93 0)
			(effects
				(font
					(size 1.27 1.27)
				)
			)
		)
		(property "Footprint" ""
			(at 214.63 78.74 0)
			(effects
				(font
					(size 1.27 1.27)
				)
				(hide yes)
			)
		)
		(property "Datasheet" ""
			(at 214.63 78.74 0)
			(effects
				(font
					(size 1.27 1.27)
				)
				(hide yes)
			)
		)
		(property "Description" ""
			(at 214.63 78.74 0)
			(effects
				(font
					(size 1.27 1.27)
				)
				(hide yes)
			)
		)
		(pin "1"
		)
		(instances
			(project "OCuLink to 10GbE adapter"
				(path ""
					(reference "#PWR0159")
					(unit 1)
				)
			)
		)
	)
	(symbol
		(lib_id "antmicropower:GND")
		(at 344.17 54.61 0)
		(unit 1)
		(exclude_from_sim no)
		(in_bom yes)
		(on_board yes)
		(dnp no)
		(property "Reference" "#PWR0126"
			(at 353.06 57.15 0)
			(effects
				(font
					(size 1.27 1.27)
					(thickness 0.15)
				)
				(justify left bottom)
				(hide yes)
			)
		)
		(property "Value" "GND"
			(at 344.17 58.42 0)
			(effects
				(font
					(size 1.27 1.27)
					(thickness 0.15)
				)
			)
		)
		(property "Footprint" ""
			(at 353.06 62.23 0)
			(effects
				(font
					(size 1.27 1.27)
					(thickness 0.15)
				)
				(justify left bottom)
				(hide yes)
			)
		)
		(property "Datasheet" ""
			(at 353.06 67.31 0)
			(effects
				(font
					(size 1.27 1.27)
					(thickness 0.15)
				)
				(justify left bottom)
				(hide yes)
			)
		)
		(property "Description" ""
			(at 344.17 54.61 0)
			(effects
				(font
					(size 1.27 1.27)
				)
				(hide yes)
			)
		)
		(property "Author" "Antmicro"
			(at 353.06 62.23 0)
			(effects
				(font
					(size 1.27 1.27)
					(thickness 0.15)
				)
				(justify left bottom)
				(hide yes)
			)
		)
		(property "License" "Apache-2.0"
			(at 353.06 64.77 0)
			(effects
				(font
					(size 1.27 1.27)
					(thickness 0.15)
				)
				(justify left bottom)
				(hide yes)
			)
		)
		(pin "1"
		)
		(instances
			(project "OCuLink to 10GbE adapter"
				(path ""
					(reference "#PWR0126")
					(unit 1)
				)
			)
		)
	)
	(symbol
		(lib_id "antmicropower:GND")
		(at 115.57 76.2 0)
		(unit 1)
		(exclude_from_sim no)
		(in_bom yes)
		(on_board yes)
		(dnp no)
		(property "Reference" "#PWR0138"
			(at 124.46 78.74 0)
			(effects
				(font
					(size 1.27 1.27)
					(thickness 0.15)
				)
				(justify left bottom)
				(hide yes)
			)
		)
		(property "Value" "GND"
			(at 115.57 80.01 0)
			(effects
				(font
					(size 1.27 1.27)
					(thickness 0.15)
				)
			)
		)
		(property "Footprint" ""
			(at 124.46 83.82 0)
			(effects
				(font
					(size 1.27 1.27)
					(thickness 0.15)
				)
				(justify left bottom)
				(hide yes)
			)
		)
		(property "Datasheet" ""
			(at 124.46 88.9 0)
			(effects
				(font
					(size 1.27 1.27)
					(thickness 0.15)
				)
				(justify left bottom)
				(hide yes)
			)
		)
		(property "Description" ""
			(at 115.57 76.2 0)
			(effects
				(font
					(size 1.27 1.27)
				)
				(hide yes)
			)
		)
		(property "Author" "Antmicro"
			(at 124.46 83.82 0)
			(effects
				(font
					(size 1.27 1.27)
					(thickness 0.15)
				)
				(justify left bottom)
				(hide yes)
			)
		)
		(property "License" "Apache-2.0"
			(at 124.46 86.36 0)
			(effects
				(font
					(size 1.27 1.27)
					(thickness 0.15)
				)
				(justify left bottom)
				(hide yes)
			)
		)
		(pin "1"
		)
		(instances
			(project "OCuLink to 10GbE adapter"
				(path ""
					(reference "#PWR0138")
					(unit 1)
				)
			)
		)
	)
	(symbol
		(lib_id "antmicroCapacitors0402:C_100n_0402")
		(at 41.91 153.67 90)
		(unit 1)
		(exclude_from_sim no)
		(in_bom yes)
		(on_board yes)
		(dnp no)
		(property "Reference" "C162"
			(at 43.942 149.86 90)
			(effects
				(font
					(size 1.27 1.27)
					(thickness 0.15)
				)
				(justify right)
			)
		)
		(property "Value" "C_100n_0402"
			(at 64.77 138.43 0)
			(effects
				(font
					(size 1.27 1.27)
					(thickness 0.15)
				)
				(justify left bottom)
				(hide yes)
			)
		)
		(property "Footprint" "antmicro-footprints:C_0402_1005Metric"
			(at 67.31 138.43 0)
			(effects
				(font
					(size 1.27 1.27)
					(thickness 0.15)
				)
				(justify left bottom)
				(hide yes)
			)
		)
		(property "Datasheet" "https://www.murata.com/products/productdetail?partno=GRM155R61H104KE14%23"
			(at 69.85 138.43 0)
			(effects
				(font
					(size 1.27 1.27)
					(thickness 0.15)
				)
				(justify left bottom)
				(hide yes)
			)
		)
		(property "Description" "SMD Multilayer Ceramic Capacitor, 0.1 µF, 50 V, 0402 [1005 Metric], ± 10%, X5R, GRM Series"
			(at 41.91 153.67 0)
			(effects
				(font
					(size 1.27 1.27)
				)
				(hide yes)
			)
		)
		(property "MPN" "GRM155R61H104KE14D"
			(at 72.39 138.43 0)
			(effects
				(font
					(size 1.27 1.27)
					(thickness 0.15)
				)
				(justify left bottom)
				(hide yes)
			)
		)
		(property "Val" "100n"
			(at 43.942 152.4 90)
			(effects
				(font
					(size 1.27 1.27)
					(thickness 0.15)
				)
				(justify right)
			)
		)
		(property "Voltage" "50V"
			(at 52.07 138.43 0)
			(effects
				(font
					(size 1.27 1.27)
					(thickness 0.15)
				)
				(justify left bottom)
				(hide yes)
			)
		)
		(property "Dielectric" "X5R"
			(at 54.61 138.43 0)
			(effects
				(font
					(size 1.27 1.27)
					(thickness 0.15)
				)
				(justify left bottom)
				(hide yes)
			)
		)
		(property "Manufacturer" "Murata"
			(at 57.15 138.43 0)
			(effects
				(font
					(size 1.27 1.27)
					(thickness 0.15)
				)
				(justify left bottom)
				(hide yes)
			)
		)
		(property "License" "Apache-2.0"
			(at 59.69 138.43 0)
			(effects
				(font
					(size 1.27 1.27)
					(thickness 0.15)
				)
				(justify left bottom)
				(hide yes)
			)
		)
		(property "Author" "Antmicro"
			(at 62.23 138.43 0)
			(effects
				(font
					(size 1.27 1.27)
					(thickness 0.15)
				)
				(justify left bottom)
				(hide yes)
			)
		)
		(pin "2"
		)
		(pin "1"
		)
		(instances
			(project ""
				(path ""
					(reference "C162")
					(unit 1)
				)
			)
		)
	)
	(symbol
		(lib_id "antmicroCapacitors0603:C_10u_10V_X7R_0603")
		(at 54.61 233.68 90)
		(unit 1)
		(exclude_from_sim no)
		(in_bom yes)
		(on_board yes)
		(dnp no)
		(property "Reference" "C186"
			(at 56.896 229.87 90)
			(effects
				(font
					(size 1.27 1.27)
					(thickness 0.15)
				)
				(justify right)
			)
		)
		(property "Value" "C_10u_10V_X7R_0603"
			(at 64.77 218.44 0)
			(effects
				(font
					(size 1.27 1.27)
					(thickness 0.15)
				)
				(justify left bottom)
				(hide yes)
			)
		)
		(property "Footprint" "antmicro-footprints:C_0603_1608Metric"
			(at 67.31 218.44 0)
			(effects
				(font
					(size 1.27 1.27)
					(thickness 0.15)
				)
				(justify left bottom)
				(hide yes)
			)
		)
		(property "Datasheet" "https://www.murata.com/products/productdetail?partno=GRM188Z71A106KA73%23"
			(at 69.85 218.44 0)
			(effects
				(font
					(size 1.27 1.27)
					(thickness 0.15)
				)
				(justify left bottom)
				(hide yes)
			)
		)
		(property "Description" "SMD Multilayer Ceramic Capacitor,  10µF, 10V, 0603, ±10%, X7R"
			(at 54.61 233.68 0)
			(effects
				(font
					(size 1.27 1.27)
				)
				(hide yes)
			)
		)
		(property "MPN" "GRM188Z71A106KA73D"
			(at 72.39 218.44 0)
			(effects
				(font
					(size 1.27 1.27)
					(thickness 0.15)
				)
				(justify left bottom)
				(hide yes)
			)
		)
		(property "Val" "10u"
			(at 56.896 232.41 90)
			(effects
				(font
					(size 1.27 1.27)
					(thickness 0.15)
				)
				(justify right)
			)
		)
		(property "Voltage" "10V"
			(at 74.93 218.44 0)
			(effects
				(font
					(size 1.27 1.27)
					(thickness 0.15)
				)
				(justify left bottom)
				(hide yes)
			)
		)
		(property "Dielectric" "X7R"
			(at 77.47 218.44 0)
			(effects
				(font
					(size 1.27 1.27)
					(thickness 0.15)
				)
				(justify left bottom)
				(hide yes)
			)
		)
		(property "Manufacturer" "Murata"
			(at 80.01 218.44 0)
			(effects
				(font
					(size 1.27 1.27)
					(thickness 0.15)
				)
				(justify left bottom)
				(hide yes)
			)
		)
		(property "License" "Apache-2.0"
			(at 82.55 218.44 0)
			(effects
				(font
					(size 1.27 1.27)
					(thickness 0.15)
				)
				(justify left bottom)
				(hide yes)
			)
		)
		(property "Author" "Antmicro"
			(at 85.09 218.44 0)
			(effects
				(font
					(size 1.27 1.27)
					(thickness 0.15)
				)
				(justify left bottom)
				(hide yes)
			)
		)
		(pin "1"
		)
		(pin "2"
		)
		(instances
			(project "OCuLink to 10GbE adapter"
				(path ""
					(reference "C186")
					(unit 1)
				)
			)
		)
	)
	(symbol
		(lib_id "antmicropower:GND")
		(at 388.62 76.2 0)
		(unit 1)
		(exclude_from_sim no)
		(in_bom yes)
		(on_board yes)
		(dnp no)
		(property "Reference" "#PWR0149"
			(at 397.51 78.74 0)
			(effects
				(font
					(size 1.27 1.27)
					(thickness 0.15)
				)
				(justify left bottom)
				(hide yes)
			)
		)
		(property "Value" "GND"
			(at 388.62 80.01 0)
			(effects
				(font
					(size 1.27 1.27)
					(thickness 0.15)
				)
			)
		)
		(property "Footprint" ""
			(at 397.51 83.82 0)
			(effects
				(font
					(size 1.27 1.27)
					(thickness 0.15)
				)
				(justify left bottom)
				(hide yes)
			)
		)
		(property "Datasheet" ""
			(at 397.51 88.9 0)
			(effects
				(font
					(size 1.27 1.27)
					(thickness 0.15)
				)
				(justify left bottom)
				(hide yes)
			)
		)
		(property "Description" ""
			(at 388.62 76.2 0)
			(effects
				(font
					(size 1.27 1.27)
				)
				(hide yes)
			)
		)
		(property "Author" "Antmicro"
			(at 397.51 83.82 0)
			(effects
				(font
					(size 1.27 1.27)
					(thickness 0.15)
				)
				(justify left bottom)
				(hide yes)
			)
		)
		(property "License" "Apache-2.0"
			(at 397.51 86.36 0)
			(effects
				(font
					(size 1.27 1.27)
					(thickness 0.15)
				)
				(justify left bottom)
				(hide yes)
			)
		)
		(pin "1"
		)
		(instances
			(project "OCuLink to 10GbE adapter"
				(path ""
					(reference "#PWR0149")
					(unit 1)
				)
			)
		)
	)
	(symbol
		(lib_id "antmicropower:GND")
		(at 115.57 182.88 0)
		(unit 1)
		(exclude_from_sim no)
		(in_bom yes)
		(on_board yes)
		(dnp no)
		(property "Reference" "#PWR0230"
			(at 124.46 185.42 0)
			(effects
				(font
					(size 1.27 1.27)
					(thickness 0.15)
				)
				(justify left bottom)
				(hide yes)
			)
		)
		(property "Value" "GND"
			(at 115.57 186.69 0)
			(effects
				(font
					(size 1.27 1.27)
					(thickness 0.15)
				)
			)
		)
		(property "Footprint" ""
			(at 124.46 190.5 0)
			(effects
				(font
					(size 1.27 1.27)
					(thickness 0.15)
				)
				(justify left bottom)
				(hide yes)
			)
		)
		(property "Datasheet" ""
			(at 124.46 195.58 0)
			(effects
				(font
					(size 1.27 1.27)
					(thickness 0.15)
				)
				(justify left bottom)
				(hide yes)
			)
		)
		(property "Description" ""
			(at 115.57 182.88 0)
			(effects
				(font
					(size 1.27 1.27)
				)
				(hide yes)
			)
		)
		(property "Author" "Antmicro"
			(at 124.46 190.5 0)
			(effects
				(font
					(size 1.27 1.27)
					(thickness 0.15)
				)
				(justify left bottom)
				(hide yes)
			)
		)
		(property "License" "Apache-2.0"
			(at 124.46 193.04 0)
			(effects
				(font
					(size 1.27 1.27)
					(thickness 0.15)
				)
				(justify left bottom)
				(hide yes)
			)
		)
		(pin "1"
		)
		(instances
			(project "OCuLink to 10GbE adapter"
				(path ""
					(reference "#PWR0230")
					(unit 1)
				)
			)
		)
	)
	(symbol
		(lib_id "antmicroCapacitors0603:C_22u_16V_0603")
		(at 62.23 52.07 90)
		(unit 1)
		(exclude_from_sim no)
		(in_bom yes)
		(on_board yes)
		(dnp no)
		(property "Reference" "C81"
			(at 64.262 48.26 90)
			(effects
				(font
					(size 1.27 1.27)
					(thickness 0.15)
				)
				(justify right)
			)
		)
		(property "Value" "C_22u_16V_0603"
			(at 72.39 31.75 0)
			(effects
				(font
					(size 1.27 1.27)
					(thickness 0.15)
				)
				(justify left bottom)
				(hide yes)
			)
		)
		(property "Footprint" "antmicro-footprints:C_0603_1608Metric_EIA"
			(at 74.93 31.75 0)
			(effects
				(font
					(size 1.27 1.27)
					(thickness 0.15)
				)
				(justify left bottom)
				(hide yes)
			)
		)
		(property "Datasheet" "https://product.samsungsem.com/mlcc/CL10A226MO7JZN.do"
			(at 77.47 31.75 0)
			(effects
				(font
					(size 1.27 1.27)
					(thickness 0.15)
				)
				(justify left bottom)
				(hide yes)
			)
		)
		(property "Description" "SMD Multilayer Ceramic Capacitor"
			(at 62.23 52.07 0)
			(effects
				(font
					(size 1.27 1.27)
				)
				(hide yes)
			)
		)
		(property "MPN" "CL10A226MO7JZNC"
			(at 80.01 31.75 0)
			(effects
				(font
					(size 1.27 1.27)
					(thickness 0.15)
				)
				(justify left bottom)
				(hide yes)
			)
		)
		(property "Manufacturer" "Samsung Electro-Mechanics"
			(at 82.55 31.75 0)
			(effects
				(font
					(size 1.27 1.27)
					(thickness 0.15)
				)
				(justify left bottom)
				(hide yes)
			)
		)
		(property "License" "Apache-2.0"
			(at 85.09 31.75 0)
			(effects
				(font
					(size 1.27 1.27)
					(thickness 0.15)
				)
				(justify left bottom)
				(hide yes)
			)
		)
		(property "Author" "Antmicro"
			(at 87.63 31.75 0)
			(effects
				(font
					(size 1.27 1.27)
					(thickness 0.15)
				)
				(justify left bottom)
				(hide yes)
			)
		)
		(property "Val" "22u"
			(at 64.262 50.8 90)
			(effects
				(font
					(size 1.27 1.27)
					(thickness 0.15)
				)
				(justify right)
			)
		)
		(property "Voltage" "16V"
			(at 90.17 31.75 0)
			(effects
				(font
					(size 1.27 1.27)
				)
				(justify left bottom)
				(hide yes)
			)
		)
		(property "Dielectric" ""
			(at 92.71 31.75 0)
			(effects
				(font
					(size 1.27 1.27)
				)
				(justify left bottom)
				(hide yes)
			)
		)
		(pin "1"
		)
		(pin "2"
		)
		(instances
			(project "OCuLink to 10GbE adapter"
				(path ""
					(reference "C81")
					(unit 1)
				)
			)
		)
	)
	(symbol
		(lib_id "antmicropower:GND")
		(at 370.84 54.61 0)
		(unit 1)
		(exclude_from_sim no)
		(in_bom yes)
		(on_board yes)
		(dnp no)
		(property "Reference" "#PWR0129"
			(at 379.73 57.15 0)
			(effects
				(font
					(size 1.27 1.27)
					(thickness 0.15)
				)
				(justify left bottom)
				(hide yes)
			)
		)
		(property "Value" "GND"
			(at 370.84 58.42 0)
			(effects
				(font
					(size 1.27 1.27)
					(thickness 0.15)
				)
			)
		)
		(property "Footprint" ""
			(at 379.73 62.23 0)
			(effects
				(font
					(size 1.27 1.27)
					(thickness 0.15)
				)
				(justify left bottom)
				(hide yes)
			)
		)
		(property "Datasheet" ""
			(at 379.73 67.31 0)
			(effects
				(font
					(size 1.27 1.27)
					(thickness 0.15)
				)
				(justify left bottom)
				(hide yes)
			)
		)
		(property "Description" ""
			(at 370.84 54.61 0)
			(effects
				(font
					(size 1.27 1.27)
				)
				(hide yes)
			)
		)
		(property "Author" "Antmicro"
			(at 379.73 62.23 0)
			(effects
				(font
					(size 1.27 1.27)
					(thickness 0.15)
				)
				(justify left bottom)
				(hide yes)
			)
		)
		(property "License" "Apache-2.0"
			(at 379.73 64.77 0)
			(effects
				(font
					(size 1.27 1.27)
					(thickness 0.15)
				)
				(justify left bottom)
				(hide yes)
			)
		)
		(pin "1"
		)
		(instances
			(project "OCuLink to 10GbE adapter"
				(path ""
					(reference "#PWR0129")
					(unit 1)
				)
			)
		)
	)
	(symbol
		(lib_id "antmicropower:GND")
		(at 326.39 93.98 0)
		(unit 1)
		(exclude_from_sim no)
		(in_bom yes)
		(on_board yes)
		(dnp no)
		(property "Reference" "#PWR0167"
			(at 335.28 96.52 0)
			(effects
				(font
					(size 1.27 1.27)
					(thickness 0.15)
				)
				(justify left bottom)
				(hide yes)
			)
		)
		(property "Value" "GND"
			(at 326.39 97.79 0)
			(effects
				(font
					(size 1.27 1.27)
					(thickness 0.15)
				)
			)
		)
		(property "Footprint" ""
			(at 335.28 101.6 0)
			(effects
				(font
					(size 1.27 1.27)
					(thickness 0.15)
				)
				(justify left bottom)
				(hide yes)
			)
		)
		(property "Datasheet" ""
			(at 335.28 106.68 0)
			(effects
				(font
					(size 1.27 1.27)
					(thickness 0.15)
				)
				(justify left bottom)
				(hide yes)
			)
		)
		(property "Description" ""
			(at 326.39 93.98 0)
			(effects
				(font
					(size 1.27 1.27)
				)
				(hide yes)
			)
		)
		(property "Author" "Antmicro"
			(at 335.28 101.6 0)
			(effects
				(font
					(size 1.27 1.27)
					(thickness 0.15)
				)
				(justify left bottom)
				(hide yes)
			)
		)
		(property "License" "Apache-2.0"
			(at 335.28 104.14 0)
			(effects
				(font
					(size 1.27 1.27)
					(thickness 0.15)
				)
				(justify left bottom)
				(hide yes)
			)
		)
		(pin "1"
		)
		(instances
			(project "OCuLink to 10GbE adapter"
				(path ""
					(reference "#PWR0167")
					(unit 1)
				)
			)
		)
	)
	(symbol
		(lib_id "antmicropower:GND")
		(at 317.5 54.61 0)
		(unit 1)
		(exclude_from_sim no)
		(in_bom yes)
		(on_board yes)
		(dnp no)
		(property "Reference" "#PWR0123"
			(at 326.39 57.15 0)
			(effects
				(font
					(size 1.27 1.27)
					(thickness 0.15)
				)
				(justify left bottom)
				(hide yes)
			)
		)
		(property "Value" "GND"
			(at 317.5 58.42 0)
			(effects
				(font
					(size 1.27 1.27)
					(thickness 0.15)
				)
			)
		)
		(property "Footprint" ""
			(at 326.39 62.23 0)
			(effects
				(font
					(size 1.27 1.27)
					(thickness 0.15)
				)
				(justify left bottom)
				(hide yes)
			)
		)
		(property "Datasheet" ""
			(at 326.39 67.31 0)
			(effects
				(font
					(size 1.27 1.27)
					(thickness 0.15)
				)
				(justify left bottom)
				(hide yes)
			)
		)
		(property "Description" ""
			(at 317.5 54.61 0)
			(effects
				(font
					(size 1.27 1.27)
				)
				(hide yes)
			)
		)
		(property "Author" "Antmicro"
			(at 326.39 62.23 0)
			(effects
				(font
					(size 1.27 1.27)
					(thickness 0.15)
				)
				(justify left bottom)
				(hide yes)
			)
		)
		(property "License" "Apache-2.0"
			(at 326.39 64.77 0)
			(effects
				(font
					(size 1.27 1.27)
					(thickness 0.15)
				)
				(justify left bottom)
				(hide yes)
			)
		)
		(pin "1"
		)
		(instances
			(project "OCuLink to 10GbE adapter"
				(path ""
					(reference "#PWR0123")
					(unit 1)
				)
			)
		)
	)
	(symbol
		(lib_id "antmicropower:GND")
		(at 361.95 54.61 0)
		(unit 1)
		(exclude_from_sim no)
		(in_bom yes)
		(on_board yes)
		(dnp no)
		(property "Reference" "#PWR0128"
			(at 370.84 57.15 0)
			(effects
				(font
					(size 1.27 1.27)
					(thickness 0.15)
				)
				(justify left bottom)
				(hide yes)
			)
		)
		(property "Value" "GND"
			(at 361.95 58.42 0)
			(effects
				(font
					(size 1.27 1.27)
					(thickness 0.15)
				)
			)
		)
		(property "Footprint" ""
			(at 370.84 62.23 0)
			(effects
				(font
					(size 1.27 1.27)
					(thickness 0.15)
				)
				(justify left bottom)
				(hide yes)
			)
		)
		(property "Datasheet" ""
			(at 370.84 67.31 0)
			(effects
				(font
					(size 1.27 1.27)
					(thickness 0.15)
				)
				(justify left bottom)
				(hide yes)
			)
		)
		(property "Description" ""
			(at 361.95 54.61 0)
			(effects
				(font
					(size 1.27 1.27)
				)
				(hide yes)
			)
		)
		(property "Author" "Antmicro"
			(at 370.84 62.23 0)
			(effects
				(font
					(size 1.27 1.27)
					(thickness 0.15)
				)
				(justify left bottom)
				(hide yes)
			)
		)
		(property "License" "Apache-2.0"
			(at 370.84 64.77 0)
			(effects
				(font
					(size 1.27 1.27)
					(thickness 0.15)
				)
				(justify left bottom)
				(hide yes)
			)
		)
		(pin "1"
		)
		(instances
			(project "OCuLink to 10GbE adapter"
				(path ""
					(reference "#PWR0128")
					(unit 1)
				)
			)
		)
	)
	(symbol
		(lib_id "antmicroCapacitors0603:C_10u_10V_X7R_0603")
		(at 71.12 153.67 90)
		(unit 1)
		(exclude_from_sim no)
		(in_bom yes)
		(on_board yes)
		(dnp no)
		(property "Reference" "C165"
			(at 73.406 149.86 90)
			(effects
				(font
					(size 1.27 1.27)
					(thickness 0.15)
				)
				(justify right)
			)
		)
		(property "Value" "C_10u_10V_X7R_0603"
			(at 81.28 138.43 0)
			(effects
				(font
					(size 1.27 1.27)
					(thickness 0.15)
				)
				(justify left bottom)
				(hide yes)
			)
		)
		(property "Footprint" "antmicro-footprints:C_0603_1608Metric"
			(at 83.82 138.43 0)
			(effects
				(font
					(size 1.27 1.27)
					(thickness 0.15)
				)
				(justify left bottom)
				(hide yes)
			)
		)
		(property "Datasheet" "https://www.murata.com/products/productdetail?partno=GRM188Z71A106KA73%23"
			(at 86.36 138.43 0)
			(effects
				(font
					(size 1.27 1.27)
					(thickness 0.15)
				)
				(justify left bottom)
				(hide yes)
			)
		)
		(property "Description" "SMD Multilayer Ceramic Capacitor,  10µF, 10V, 0603, ±10%, X7R"
			(at 71.12 153.67 0)
			(effects
				(font
					(size 1.27 1.27)
				)
				(hide yes)
			)
		)
		(property "MPN" "GRM188Z71A106KA73D"
			(at 88.9 138.43 0)
			(effects
				(font
					(size 1.27 1.27)
					(thickness 0.15)
				)
				(justify left bottom)
				(hide yes)
			)
		)
		(property "Val" "10u"
			(at 73.406 152.4 90)
			(effects
				(font
					(size 1.27 1.27)
					(thickness 0.15)
				)
				(justify right)
			)
		)
		(property "Voltage" "10V"
			(at 91.44 138.43 0)
			(effects
				(font
					(size 1.27 1.27)
					(thickness 0.15)
				)
				(justify left bottom)
				(hide yes)
			)
		)
		(property "Dielectric" "X7R"
			(at 93.98 138.43 0)
			(effects
				(font
					(size 1.27 1.27)
					(thickness 0.15)
				)
				(justify left bottom)
				(hide yes)
			)
		)
		(property "Manufacturer" "Murata"
			(at 96.52 138.43 0)
			(effects
				(font
					(size 1.27 1.27)
					(thickness 0.15)
				)
				(justify left bottom)
				(hide yes)
			)
		)
		(property "License" "Apache-2.0"
			(at 99.06 138.43 0)
			(effects
				(font
					(size 1.27 1.27)
					(thickness 0.15)
				)
				(justify left bottom)
				(hide yes)
			)
		)
		(property "Author" "Antmicro"
			(at 101.6 138.43 0)
			(effects
				(font
					(size 1.27 1.27)
					(thickness 0.15)
				)
				(justify left bottom)
				(hide yes)
			)
		)
		(pin "1"
		)
		(pin "2"
		)
		(instances
			(project "OCuLink to 10GbE adapter"
				(path ""
					(reference "C165")
					(unit 1)
				)
			)
		)
	)
	(symbol
		(lib_id "antmicropower:GND")
		(at 344.17 115.57 0)
		(unit 1)
		(exclude_from_sim no)
		(in_bom yes)
		(on_board yes)
		(dnp no)
		(property "Reference" "#PWR0182"
			(at 353.06 118.11 0)
			(effects
				(font
					(size 1.27 1.27)
					(thickness 0.15)
				)
				(justify left bottom)
				(hide yes)
			)
		)
		(property "Value" "GND"
			(at 344.17 119.38 0)
			(effects
				(font
					(size 1.27 1.27)
					(thickness 0.15)
				)
			)
		)
		(property "Footprint" ""
			(at 353.06 123.19 0)
			(effects
				(font
					(size 1.27 1.27)
					(thickness 0.15)
				)
				(justify left bottom)
				(hide yes)
			)
		)
		(property "Datasheet" ""
			(at 353.06 128.27 0)
			(effects
				(font
					(size 1.27 1.27)
					(thickness 0.15)
				)
				(justify left bottom)
				(hide yes)
			)
		)
		(property "Description" ""
			(at 344.17 115.57 0)
			(effects
				(font
					(size 1.27 1.27)
				)
				(hide yes)
			)
		)
		(property "Author" "Antmicro"
			(at 353.06 123.19 0)
			(effects
				(font
					(size 1.27 1.27)
					(thickness 0.15)
				)
				(justify left bottom)
				(hide yes)
			)
		)
		(property "License" "Apache-2.0"
			(at 353.06 125.73 0)
			(effects
				(font
					(size 1.27 1.27)
					(thickness 0.15)
				)
				(justify left bottom)
				(hide yes)
			)
		)
		(pin "1"
		)
		(instances
			(project "OCuLink to 10GbE adapter"
				(path ""
					(reference "#PWR0182")
					(unit 1)
				)
			)
		)
	)
	(symbol
		(lib_id "antmicroCapacitors0603:C_10u_10V_X7R_0603")
		(at 326.39 130.81 90)
		(unit 1)
		(exclude_from_sim no)
		(in_bom yes)
		(on_board yes)
		(dnp no)
		(property "Reference" "C149"
			(at 328.422 127 90)
			(effects
				(font
					(size 1.27 1.27)
					(thickness 0.15)
				)
				(justify right)
			)
		)
		(property "Value" "C_10u_10V_X7R_0603"
			(at 336.55 115.57 0)
			(effects
				(font
					(size 1.27 1.27)
					(thickness 0.15)
				)
				(justify left bottom)
				(hide yes)
			)
		)
		(property "Footprint" "antmicro-footprints:C_0603_1608Metric"
			(at 339.09 115.57 0)
			(effects
				(font
					(size 1.27 1.27)
					(thickness 0.15)
				)
				(justify left bottom)
				(hide yes)
			)
		)
		(property "Datasheet" "https://www.murata.com/products/productdetail?partno=GRM188Z71A106KA73%23"
			(at 341.63 115.57 0)
			(effects
				(font
					(size 1.27 1.27)
					(thickness 0.15)
				)
				(justify left bottom)
				(hide yes)
			)
		)
		(property "Description" "SMD Multilayer Ceramic Capacitor,  10µF, 10V, 0603, ±10%, X7R"
			(at 326.39 130.81 0)
			(effects
				(font
					(size 1.27 1.27)
				)
				(hide yes)
			)
		)
		(property "MPN" "GRM188Z71A106KA73D"
			(at 344.17 115.57 0)
			(effects
				(font
					(size 1.27 1.27)
					(thickness 0.15)
				)
				(justify left bottom)
				(hide yes)
			)
		)
		(property "Val" "10u"
			(at 328.422 129.54 90)
			(effects
				(font
					(size 1.27 1.27)
					(thickness 0.15)
				)
				(justify right)
			)
		)
		(property "Voltage" "10V"
			(at 346.71 115.57 0)
			(effects
				(font
					(size 1.27 1.27)
					(thickness 0.15)
				)
				(justify left bottom)
				(hide yes)
			)
		)
		(property "Dielectric" "X7R"
			(at 349.25 115.57 0)
			(effects
				(font
					(size 1.27 1.27)
					(thickness 0.15)
				)
				(justify left bottom)
				(hide yes)
			)
		)
		(property "Manufacturer" "Murata"
			(at 351.79 115.57 0)
			(effects
				(font
					(size 1.27 1.27)
					(thickness 0.15)
				)
				(justify left bottom)
				(hide yes)
			)
		)
		(property "License" "Apache-2.0"
			(at 354.33 115.57 0)
			(effects
				(font
					(size 1.27 1.27)
					(thickness 0.15)
				)
				(justify left bottom)
				(hide yes)
			)
		)
		(property "Author" "Antmicro"
			(at 356.87 115.57 0)
			(effects
				(font
					(size 1.27 1.27)
					(thickness 0.15)
				)
				(justify left bottom)
				(hide yes)
			)
		)
		(pin "1"
		)
		(pin "2"
		)
		(instances
			(project "OCuLink to 10GbE adapter"
				(path ""
					(reference "C149")
					(unit 1)
				)
			)
		)
	)
	(symbol
		(lib_id "antmicroCapacitors0402:C_1u_25V_0402")
		(at 88.9 52.07 90)
		(unit 1)
		(exclude_from_sim no)
		(in_bom yes)
		(on_board yes)
		(dnp no)
		(property "Reference" "C83"
			(at 90.932 48.26 90)
			(effects
				(font
					(size 1.27 1.27)
					(thickness 0.15)
				)
				(justify right)
			)
		)
		(property "Value" "C_1u_25V_0402"
			(at 99.06 31.75 0)
			(effects
				(font
					(size 1.27 1.27)
					(thickness 0.15)
				)
				(justify left bottom)
				(hide yes)
			)
		)
		(property "Footprint" "antmicro-footprints:C_0402_1005Metric"
			(at 101.6 31.75 0)
			(effects
				(font
					(size 1.27 1.27)
					(thickness 0.15)
				)
				(justify left bottom)
				(hide yes)
			)
		)
		(property "Datasheet" "https://www.murata.com/products/productdetail?partno=GRM155R61E105KE11%23"
			(at 104.14 31.75 0)
			(effects
				(font
					(size 1.27 1.27)
					(thickness 0.15)
				)
				(justify left bottom)
				(hide yes)
			)
		)
		(property "Description" "SMD Multilayer Ceramic Capacitor, 1 µF, 25 V, 0402 [1005 Metric], ± 10%, X5R, GRM Series"
			(at 88.9 52.07 0)
			(effects
				(font
					(size 1.27 1.27)
				)
				(hide yes)
			)
		)
		(property "MPN" "GRM155R61E105KE11J"
			(at 106.68 31.75 0)
			(effects
				(font
					(size 1.27 1.27)
					(thickness 0.15)
				)
				(justify left bottom)
				(hide yes)
			)
		)
		(property "Manufacturer" "Murata"
			(at 109.22 31.75 0)
			(effects
				(font
					(size 1.27 1.27)
					(thickness 0.15)
				)
				(justify left bottom)
				(hide yes)
			)
		)
		(property "License" "Apache-2.0"
			(at 111.76 31.75 0)
			(effects
				(font
					(size 1.27 1.27)
					(thickness 0.15)
				)
				(justify left bottom)
				(hide yes)
			)
		)
		(property "Author" "Antmicro"
			(at 114.3 31.75 0)
			(effects
				(font
					(size 1.27 1.27)
					(thickness 0.15)
				)
				(justify left bottom)
				(hide yes)
			)
		)
		(property "Val" "1u"
			(at 90.932 50.8 90)
			(effects
				(font
					(size 1.27 1.27)
					(thickness 0.15)
				)
				(justify right)
			)
		)
		(property "Voltage" "25V"
			(at 116.84 31.75 0)
			(effects
				(font
					(size 1.27 1.27)
				)
				(justify left bottom)
				(hide yes)
			)
		)
		(property "Dielectric" "X5R"
			(at 119.38 31.75 0)
			(effects
				(font
					(size 1.27 1.27)
				)
				(justify left bottom)
				(hide yes)
			)
		)
		(pin "2"
		)
		(pin "1"
		)
		(instances
			(project "OCuLink to 10GbE adapter"
				(path ""
					(reference "C83")
					(unit 1)
				)
			)
		)
	)
	(symbol
		(lib_id "antmicroCapacitors0603:C_22u_16V_0603")
		(at 31.75 153.67 90)
		(unit 1)
		(exclude_from_sim no)
		(in_bom yes)
		(on_board yes)
		(dnp no)
		(property "Reference" "C161"
			(at 33.782 149.86 90)
			(effects
				(font
					(size 1.27 1.27)
					(thickness 0.15)
				)
				(justify right)
			)
		)
		(property "Value" "C_22u_16V_0603"
			(at 41.91 133.35 0)
			(effects
				(font
					(size 1.27 1.27)
					(thickness 0.15)
				)
				(justify left bottom)
				(hide yes)
			)
		)
		(property "Footprint" "antmicro-footprints:C_0603_1608Metric_EIA"
			(at 44.45 133.35 0)
			(effects
				(font
					(size 1.27 1.27)
					(thickness 0.15)
				)
				(justify left bottom)
				(hide yes)
			)
		)
		(property "Datasheet" "https://product.samsungsem.com/mlcc/CL10A226MO7JZN.do"
			(at 46.99 133.35 0)
			(effects
				(font
					(size 1.27 1.27)
					(thickness 0.15)
				)
				(justify left bottom)
				(hide yes)
			)
		)
		(property "Description" "SMD Multilayer Ceramic Capacitor"
			(at 31.75 153.67 0)
			(effects
				(font
					(size 1.27 1.27)
				)
				(hide yes)
			)
		)
		(property "MPN" "CL10A226MO7JZNC"
			(at 49.53 133.35 0)
			(effects
				(font
					(size 1.27 1.27)
					(thickness 0.15)
				)
				(justify left bottom)
				(hide yes)
			)
		)
		(property "Manufacturer" "Samsung Electro-Mechanics"
			(at 52.07 133.35 0)
			(effects
				(font
					(size 1.27 1.27)
					(thickness 0.15)
				)
				(justify left bottom)
				(hide yes)
			)
		)
		(property "License" "Apache-2.0"
			(at 54.61 133.35 0)
			(effects
				(font
					(size 1.27 1.27)
					(thickness 0.15)
				)
				(justify left bottom)
				(hide yes)
			)
		)
		(property "Author" "Antmicro"
			(at 57.15 133.35 0)
			(effects
				(font
					(size 1.27 1.27)
					(thickness 0.15)
				)
				(justify left bottom)
				(hide yes)
			)
		)
		(property "Val" "22u"
			(at 33.782 152.4 90)
			(effects
				(font
					(size 1.27 1.27)
					(thickness 0.15)
				)
				(justify right)
			)
		)
		(property "Voltage" "16V"
			(at 59.69 133.35 0)
			(effects
				(font
					(size 1.27 1.27)
				)
				(justify left bottom)
				(hide yes)
			)
		)
		(property "Dielectric" ""
			(at 62.23 133.35 0)
			(effects
				(font
					(size 1.27 1.27)
				)
				(justify left bottom)
				(hide yes)
			)
		)
		(pin "1"
		)
		(pin "2"
		)
		(instances
			(project "OCuLink to 10GbE adapter"
				(path ""
					(reference "C161")
					(unit 1)
				)
			)
		)
	)
	(symbol
		(lib_id "antmicroTestPoints:TP_1mm_SMD")
		(at 238.76 179.07 0)
		(unit 1)
		(exclude_from_sim no)
		(in_bom no)
		(on_board yes)
		(dnp no)
		(fields_autoplaced yes)
		(property "Reference" "TP35"
			(at 243.84 179.07 0)
			(effects
				(font
					(size 1.27 1.27)
					(thickness 0.15)
				)
				(justify left)
			)
		)
		(property "Value" "TP_1mm_SMD"
			(at 254 186.69 0)
			(effects
				(font
					(size 1.27 1.27)
					(thickness 0.15)
				)
				(justify left bottom)
				(hide yes)
			)
		)
		(property "Footprint" "antmicro-footprints:TP_SMD_1mm"
			(at 254 189.23 0)
			(effects
				(font
					(size 1.27 1.27)
					(thickness 0.15)
				)
				(justify left bottom)
				(hide yes)
			)
		)
		(property "Datasheet" ""
			(at 256.54 191.77 0)
			(effects
				(font
					(size 1.27 1.27)
					(thickness 0.15)
				)
				(justify left bottom)
				(hide yes)
			)
		)
		(property "Description" "Test point 1mm SMD"
			(at 254 199.39 0)
			(effects
				(font
					(size 1.27 1.27)
				)
				(justify left bottom)
				(hide yes)
			)
		)
		(property "MPN" ""
			(at 238.76 179.07 0)
			(effects
				(font
					(size 1.27 1.27)
				)
				(hide yes)
			)
		)
		(property "Manufacturer" ""
			(at 238.76 179.07 0)
			(effects
				(font
					(size 1.27 1.27)
				)
				(hide yes)
			)
		)
		(property "Author" "Antmicro"
			(at 254 194.31 0)
			(effects
				(font
					(size 1.27 1.27)
					(thickness 0.15)
				)
				(justify left bottom)
				(hide yes)
			)
		)
		(property "License" "Apache-2.0"
			(at 254 196.85 0)
			(effects
				(font
					(size 1.27 1.27)
					(thickness 0.15)
				)
				(justify left bottom)
				(hide yes)
			)
		)
		(pin "1"
		)
		(instances
			(project "oculink-to-10gbe-adapter"
				(path ""
					(reference "TP35")
					(unit 1)
				)
			)
		)
	)
	(symbol
		(lib_id "antmicroCapacitors0603:C_22u_16V_0603")
		(at 44.45 52.07 90)
		(unit 1)
		(exclude_from_sim no)
		(in_bom yes)
		(on_board yes)
		(dnp no)
		(property "Reference" "C79"
			(at 46.482 48.26 90)
			(effects
				(font
					(size 1.27 1.27)
					(thickness 0.15)
				)
				(justify right)
			)
		)
		(property "Value" "C_22u_16V_0603"
			(at 54.61 31.75 0)
			(effects
				(font
					(size 1.27 1.27)
					(thickness 0.15)
				)
				(justify left bottom)
				(hide yes)
			)
		)
		(property "Footprint" "antmicro-footprints:C_0603_1608Metric_EIA"
			(at 57.15 31.75 0)
			(effects
				(font
					(size 1.27 1.27)
					(thickness 0.15)
				)
				(justify left bottom)
				(hide yes)
			)
		)
		(property "Datasheet" "https://product.samsungsem.com/mlcc/CL10A226MO7JZN.do"
			(at 59.69 31.75 0)
			(effects
				(font
					(size 1.27 1.27)
					(thickness 0.15)
				)
				(justify left bottom)
				(hide yes)
			)
		)
		(property "Description" "SMD Multilayer Ceramic Capacitor"
			(at 44.45 52.07 0)
			(effects
				(font
					(size 1.27 1.27)
				)
				(hide yes)
			)
		)
		(property "MPN" "CL10A226MO7JZNC"
			(at 62.23 31.75 0)
			(effects
				(font
					(size 1.27 1.27)
					(thickness 0.15)
				)
				(justify left bottom)
				(hide yes)
			)
		)
		(property "Manufacturer" "Samsung Electro-Mechanics"
			(at 64.77 31.75 0)
			(effects
				(font
					(size 1.27 1.27)
					(thickness 0.15)
				)
				(justify left bottom)
				(hide yes)
			)
		)
		(property "License" "Apache-2.0"
			(at 67.31 31.75 0)
			(effects
				(font
					(size 1.27 1.27)
					(thickness 0.15)
				)
				(justify left bottom)
				(hide yes)
			)
		)
		(property "Author" "Antmicro"
			(at 69.85 31.75 0)
			(effects
				(font
					(size 1.27 1.27)
					(thickness 0.15)
				)
				(justify left bottom)
				(hide yes)
			)
		)
		(property "Val" "22u"
			(at 46.482 50.8 90)
			(effects
				(font
					(size 1.27 1.27)
					(thickness 0.15)
				)
				(justify right)
			)
		)
		(property "Voltage" "16V"
			(at 72.39 31.75 0)
			(effects
				(font
					(size 1.27 1.27)
				)
				(justify left bottom)
				(hide yes)
			)
		)
		(property "Dielectric" ""
			(at 74.93 31.75 0)
			(effects
				(font
					(size 1.27 1.27)
				)
				(justify left bottom)
				(hide yes)
			)
		)
		(pin "1"
		)
		(pin "2"
		)
		(instances
			(project "OCuLink to 10GbE adapter"
				(path ""
					(reference "C79")
					(unit 1)
				)
			)
		)
	)
	(symbol
		(lib_id "antmicroCapacitors0402:C_1u_25V_0402")
		(at 379.73 73.66 90)
		(unit 1)
		(exclude_from_sim no)
		(in_bom yes)
		(on_board yes)
		(dnp no)
		(property "Reference" "C114"
			(at 381.762 69.85 90)
			(effects
				(font
					(size 1.27 1.27)
					(thickness 0.15)
				)
				(justify right)
			)
		)
		(property "Value" "C_1u_25V_0402"
			(at 389.89 53.34 0)
			(effects
				(font
					(size 1.27 1.27)
					(thickness 0.15)
				)
				(justify left bottom)
				(hide yes)
			)
		)
		(property "Footprint" "antmicro-footprints:C_0402_1005Metric"
			(at 392.43 53.34 0)
			(effects
				(font
					(size 1.27 1.27)
					(thickness 0.15)
				)
				(justify left bottom)
				(hide yes)
			)
		)
		(property "Datasheet" "https://www.murata.com/products/productdetail?partno=GRM155R61E105KE11%23"
			(at 394.97 53.34 0)
			(effects
				(font
					(size 1.27 1.27)
					(thickness 0.15)
				)
				(justify left bottom)
				(hide yes)
			)
		)
		(property "Description" "SMD Multilayer Ceramic Capacitor, 1 µF, 25 V, 0402 [1005 Metric], ± 10%, X5R, GRM Series"
			(at 379.73 73.66 0)
			(effects
				(font
					(size 1.27 1.27)
				)
				(hide yes)
			)
		)
		(property "MPN" "GRM155R61E105KE11J"
			(at 397.51 53.34 0)
			(effects
				(font
					(size 1.27 1.27)
					(thickness 0.15)
				)
				(justify left bottom)
				(hide yes)
			)
		)
		(property "Manufacturer" "Murata"
			(at 400.05 53.34 0)
			(effects
				(font
					(size 1.27 1.27)
					(thickness 0.15)
				)
				(justify left bottom)
				(hide yes)
			)
		)
		(property "License" "Apache-2.0"
			(at 402.59 53.34 0)
			(effects
				(font
					(size 1.27 1.27)
					(thickness 0.15)
				)
				(justify left bottom)
				(hide yes)
			)
		)
		(property "Author" "Antmicro"
			(at 405.13 53.34 0)
			(effects
				(font
					(size 1.27 1.27)
					(thickness 0.15)
				)
				(justify left bottom)
				(hide yes)
			)
		)
		(property "Val" "1u"
			(at 381.762 72.39 90)
			(effects
				(font
					(size 1.27 1.27)
					(thickness 0.15)
				)
				(justify right)
			)
		)
		(property "Voltage" "25V"
			(at 407.67 53.34 0)
			(effects
				(font
					(size 1.27 1.27)
				)
				(justify left bottom)
				(hide yes)
			)
		)
		(property "Dielectric" "X5R"
			(at 410.21 53.34 0)
			(effects
				(font
					(size 1.27 1.27)
				)
				(justify left bottom)
				(hide yes)
			)
		)
		(pin "2"
		)
		(pin "1"
		)
		(instances
			(project "OCuLink to 10GbE adapter"
				(path ""
					(reference "C114")
					(unit 1)
				)
			)
		)
	)
	(symbol
		(lib_id "antmicroCapacitors0402:C_1u_25V_0402")
		(at 88.9 153.67 90)
		(unit 1)
		(exclude_from_sim no)
		(in_bom yes)
		(on_board yes)
		(dnp no)
		(property "Reference" "C166"
			(at 90.932 149.86 90)
			(effects
				(font
					(size 1.27 1.27)
					(thickness 0.15)
				)
				(justify right)
			)
		)
		(property "Value" "C_1u_25V_0402"
			(at 99.06 133.35 0)
			(effects
				(font
					(size 1.27 1.27)
					(thickness 0.15)
				)
				(justify left bottom)
				(hide yes)
			)
		)
		(property "Footprint" "antmicro-footprints:C_0402_1005Metric"
			(at 101.6 133.35 0)
			(effects
				(font
					(size 1.27 1.27)
					(thickness 0.15)
				)
				(justify left bottom)
				(hide yes)
			)
		)
		(property "Datasheet" "https://www.murata.com/products/productdetail?partno=GRM155R61E105KE11%23"
			(at 104.14 133.35 0)
			(effects
				(font
					(size 1.27 1.27)
					(thickness 0.15)
				)
				(justify left bottom)
				(hide yes)
			)
		)
		(property "Description" "SMD Multilayer Ceramic Capacitor, 1 µF, 25 V, 0402 [1005 Metric], ± 10%, X5R, GRM Series"
			(at 88.9 153.67 0)
			(effects
				(font
					(size 1.27 1.27)
				)
				(hide yes)
			)
		)
		(property "MPN" "GRM155R61E105KE11J"
			(at 106.68 133.35 0)
			(effects
				(font
					(size 1.27 1.27)
					(thickness 0.15)
				)
				(justify left bottom)
				(hide yes)
			)
		)
		(property "Manufacturer" "Murata"
			(at 109.22 133.35 0)
			(effects
				(font
					(size 1.27 1.27)
					(thickness 0.15)
				)
				(justify left bottom)
				(hide yes)
			)
		)
		(property "License" "Apache-2.0"
			(at 111.76 133.35 0)
			(effects
				(font
					(size 1.27 1.27)
					(thickness 0.15)
				)
				(justify left bottom)
				(hide yes)
			)
		)
		(property "Author" "Antmicro"
			(at 114.3 133.35 0)
			(effects
				(font
					(size 1.27 1.27)
					(thickness 0.15)
				)
				(justify left bottom)
				(hide yes)
			)
		)
		(property "Val" "1u"
			(at 90.932 152.4 90)
			(effects
				(font
					(size 1.27 1.27)
					(thickness 0.15)
				)
				(justify right)
			)
		)
		(property "Voltage" "25V"
			(at 116.84 133.35 0)
			(effects
				(font
					(size 1.27 1.27)
				)
				(justify left bottom)
				(hide yes)
			)
		)
		(property "Dielectric" "X5R"
			(at 119.38 133.35 0)
			(effects
				(font
					(size 1.27 1.27)
				)
				(justify left bottom)
				(hide yes)
			)
		)
		(pin "2"
		)
		(pin "1"
		)
		(instances
			(project "OCuLink to 10GbE adapter"
				(path ""
					(reference "C166")
					(unit 1)
				)
			)
		)
	)
	(symbol
		(lib_id "antmicropower:GND")
		(at 379.73 54.61 0)
		(unit 1)
		(exclude_from_sim no)
		(in_bom yes)
		(on_board yes)
		(dnp no)
		(property "Reference" "#PWR0130"
			(at 388.62 57.15 0)
			(effects
				(font
					(size 1.27 1.27)
					(thickness 0.15)
				)
				(justify left bottom)
				(hide yes)
			)
		)
		(property "Value" "GND"
			(at 379.73 58.42 0)
			(effects
				(font
					(size 1.27 1.27)
					(thickness 0.15)
				)
			)
		)
		(property "Footprint" ""
			(at 388.62 62.23 0)
			(effects
				(font
					(size 1.27 1.27)
					(thickness 0.15)
				)
				(justify left bottom)
				(hide yes)
			)
		)
		(property "Datasheet" ""
			(at 388.62 67.31 0)
			(effects
				(font
					(size 1.27 1.27)
					(thickness 0.15)
				)
				(justify left bottom)
				(hide yes)
			)
		)
		(property "Description" ""
			(at 379.73 54.61 0)
			(effects
				(font
					(size 1.27 1.27)
				)
				(hide yes)
			)
		)
		(property "Author" "Antmicro"
			(at 388.62 62.23 0)
			(effects
				(font
					(size 1.27 1.27)
					(thickness 0.15)
				)
				(justify left bottom)
				(hide yes)
			)
		)
		(property "License" "Apache-2.0"
			(at 388.62 64.77 0)
			(effects
				(font
					(size 1.27 1.27)
					(thickness 0.15)
				)
				(justify left bottom)
				(hide yes)
			)
		)
		(pin "1"
		)
		(instances
			(project "OCuLink to 10GbE adapter"
				(path ""
					(reference "#PWR0130")
					(unit 1)
				)
			)
		)
	)
	(symbol
		(lib_id "antmicropower:GND")
		(at 21.59 156.21 0)
		(unit 1)
		(exclude_from_sim no)
		(in_bom yes)
		(on_board yes)
		(dnp no)
		(property "Reference" "#PWR0211"
			(at 30.48 158.75 0)
			(effects
				(font
					(size 1.27 1.27)
					(thickness 0.15)
				)
				(justify left bottom)
				(hide yes)
			)
		)
		(property "Value" "GND"
			(at 21.59 160.02 0)
			(effects
				(font
					(size 1.27 1.27)
					(thickness 0.15)
				)
			)
		)
		(property "Footprint" ""
			(at 30.48 163.83 0)
			(effects
				(font
					(size 1.27 1.27)
					(thickness 0.15)
				)
				(justify left bottom)
				(hide yes)
			)
		)
		(property "Datasheet" ""
			(at 30.48 168.91 0)
			(effects
				(font
					(size 1.27 1.27)
					(thickness 0.15)
				)
				(justify left bottom)
				(hide yes)
			)
		)
		(property "Description" ""
			(at 21.59 156.21 0)
			(effects
				(font
					(size 1.27 1.27)
				)
				(hide yes)
			)
		)
		(property "Author" "Antmicro"
			(at 30.48 163.83 0)
			(effects
				(font
					(size 1.27 1.27)
					(thickness 0.15)
				)
				(justify left bottom)
				(hide yes)
			)
		)
		(property "License" "Apache-2.0"
			(at 30.48 166.37 0)
			(effects
				(font
					(size 1.27 1.27)
					(thickness 0.15)
				)
				(justify left bottom)
				(hide yes)
			)
		)
		(pin "1"
		)
		(instances
			(project "OCuLink to 10GbE adapter"
				(path ""
					(reference "#PWR0211")
					(unit 1)
				)
			)
		)
	)
	(symbol
		(lib_id "antmicroCapacitorsmisc:C_100u_0805")
		(at 62.23 153.67 90)
		(unit 1)
		(exclude_from_sim no)
		(in_bom yes)
		(on_board yes)
		(dnp no)
		(property "Reference" "C164"
			(at 64.008 149.86 90)
			(effects
				(font
					(size 1.27 1.27)
					(thickness 0.15)
				)
				(justify right)
			)
		)
		(property "Value" "C_100u_0805"
			(at 72.39 133.35 0)
			(effects
				(font
					(size 1.27 1.27)
					(thickness 0.15)
				)
				(justify left bottom)
				(hide yes)
			)
		)
		(property "Footprint" "antmicro-footprints:C_0805_2012Metric"
			(at 74.93 133.35 0)
			(effects
				(font
					(size 1.27 1.27)
					(thickness 0.15)
				)
				(justify left bottom)
				(hide yes)
			)
		)
		(property "Datasheet" "https://www.murata.com/products/productdetail?partno=GRM21BR60J107ME15%23"
			(at 77.47 133.35 0)
			(effects
				(font
					(size 1.27 1.27)
					(thickness 0.15)
				)
				(justify left bottom)
				(hide yes)
			)
		)
		(property "Description" "SMD Multilayer Ceramic Capacitor, 100 µF, 6.3 V, 0805 [2012 Metric], ± 20%, X5R, GRM Series"
			(at 62.23 153.67 0)
			(effects
				(font
					(size 1.27 1.27)
				)
				(hide yes)
			)
		)
		(property "MPN" "GRM21BR60J107ME15L"
			(at 80.01 133.35 0)
			(effects
				(font
					(size 1.27 1.27)
					(thickness 0.15)
				)
				(justify left bottom)
				(hide yes)
			)
		)
		(property "Manufacturer" "Murata"
			(at 82.55 133.35 0)
			(effects
				(font
					(size 1.27 1.27)
					(thickness 0.15)
				)
				(justify left bottom)
				(hide yes)
			)
		)
		(property "License" "Apache-2.0"
			(at 85.09 133.35 0)
			(effects
				(font
					(size 1.27 1.27)
					(thickness 0.15)
				)
				(justify left bottom)
				(hide yes)
			)
		)
		(property "Author" "Antmicro"
			(at 87.63 133.35 0)
			(effects
				(font
					(size 1.27 1.27)
					(thickness 0.15)
				)
				(justify left bottom)
				(hide yes)
			)
		)
		(property "Val" "100u"
			(at 64.008 152.4 90)
			(effects
				(font
					(size 1.27 1.27)
					(thickness 0.15)
				)
				(justify right)
			)
		)
		(property "Voltage" ""
			(at 90.17 133.35 0)
			(effects
				(font
					(size 1.27 1.27)
				)
				(justify left bottom)
				(hide yes)
			)
		)
		(property "Dielectric" ""
			(at 92.71 133.35 0)
			(effects
				(font
					(size 1.27 1.27)
				)
				(justify left bottom)
				(hide yes)
			)
		)
		(property "Public" "False"
			(at 95.25 133.35 0)
			(effects
				(font
					(size 1.27 1.27)
				)
				(justify left bottom)
				(hide yes)
			)
		)
		(pin "1"
		)
		(pin "2"
		)
		(instances
			(project "OCuLink to 10GbE adapter"
				(path ""
					(reference "C164")
					(unit 1)
				)
			)
		)
	)
	(symbol
		(lib_id "antmicropower:GND")
		(at 115.57 209.55 0)
		(unit 1)
		(exclude_from_sim no)
		(in_bom yes)
		(on_board yes)
		(dnp no)
		(property "Reference" "#PWR0237"
			(at 124.46 212.09 0)
			(effects
				(font
					(size 1.27 1.27)
					(thickness 0.15)
				)
				(justify left bottom)
				(hide yes)
			)
		)
		(property "Value" "GND"
			(at 115.57 213.36 0)
			(effects
				(font
					(size 1.27 1.27)
					(thickness 0.15)
				)
			)
		)
		(property "Footprint" ""
			(at 124.46 217.17 0)
			(effects
				(font
					(size 1.27 1.27)
					(thickness 0.15)
				)
				(justify left bottom)
				(hide yes)
			)
		)
		(property "Datasheet" ""
			(at 124.46 222.25 0)
			(effects
				(font
					(size 1.27 1.27)
					(thickness 0.15)
				)
				(justify left bottom)
				(hide yes)
			)
		)
		(property "Description" ""
			(at 115.57 209.55 0)
			(effects
				(font
					(size 1.27 1.27)
				)
				(hide yes)
			)
		)
		(property "Author" "Antmicro"
			(at 124.46 217.17 0)
			(effects
				(font
					(size 1.27 1.27)
					(thickness 0.15)
				)
				(justify left bottom)
				(hide yes)
			)
		)
		(property "License" "Apache-2.0"
			(at 124.46 219.71 0)
			(effects
				(font
					(size 1.27 1.27)
					(thickness 0.15)
				)
				(justify left bottom)
				(hide yes)
			)
		)
		(pin "1"
		)
		(instances
			(project "OCuLink to 10GbE adapter"
				(path ""
					(reference "#PWR0237")
					(unit 1)
				)
			)
		)
	)
	(symbol
		(lib_id "antmicropower:GND")
		(at 88.9 129.54 0)
		(unit 1)
		(exclude_from_sim no)
		(in_bom yes)
		(on_board yes)
		(dnp no)
		(property "Reference" "#PWR0191"
			(at 97.79 132.08 0)
			(effects
				(font
					(size 1.27 1.27)
					(thickness 0.15)
				)
				(justify left bottom)
				(hide yes)
			)
		)
		(property "Value" "GND"
			(at 88.9 133.35 0)
			(effects
				(font
					(size 1.27 1.27)
					(thickness 0.15)
				)
			)
		)
		(property "Footprint" ""
			(at 97.79 137.16 0)
			(effects
				(font
					(size 1.27 1.27)
					(thickness 0.15)
				)
				(justify left bottom)
				(hide yes)
			)
		)
		(property "Datasheet" ""
			(at 97.79 142.24 0)
			(effects
				(font
					(size 1.27 1.27)
					(thickness 0.15)
				)
				(justify left bottom)
				(hide yes)
			)
		)
		(property "Description" ""
			(at 88.9 129.54 0)
			(effects
				(font
					(size 1.27 1.27)
				)
				(hide yes)
			)
		)
		(property "Author" "Antmicro"
			(at 97.79 137.16 0)
			(effects
				(font
					(size 1.27 1.27)
					(thickness 0.15)
				)
				(justify left bottom)
				(hide yes)
			)
		)
		(property "License" "Apache-2.0"
			(at 97.79 139.7 0)
			(effects
				(font
					(size 1.27 1.27)
					(thickness 0.15)
				)
				(justify left bottom)
				(hide yes)
			)
		)
		(pin "1"
		)
		(instances
			(project "OCuLink to 10GbE adapter"
				(path ""
					(reference "#PWR0191")
					(unit 1)
				)
			)
		)
	)
	(symbol
		(lib_id "antmicroCapacitors0603:C_10u_10V_X7R_0603")
		(at 53.34 127 90)
		(unit 1)
		(exclude_from_sim no)
		(in_bom yes)
		(on_board yes)
		(dnp no)
		(property "Reference" "C139"
			(at 55.118 123.19 90)
			(effects
				(font
					(size 1.27 1.27)
					(thickness 0.15)
				)
				(justify right)
			)
		)
		(property "Value" "C_10u_10V_X7R_0603"
			(at 63.5 111.76 0)
			(effects
				(font
					(size 1.27 1.27)
					(thickness 0.15)
				)
				(justify left bottom)
				(hide yes)
			)
		)
		(property "Footprint" "antmicro-footprints:C_0603_1608Metric"
			(at 66.04 111.76 0)
			(effects
				(font
					(size 1.27 1.27)
					(thickness 0.15)
				)
				(justify left bottom)
				(hide yes)
			)
		)
		(property "Datasheet" "https://www.murata.com/products/productdetail?partno=GRM188Z71A106KA73%23"
			(at 68.58 111.76 0)
			(effects
				(font
					(size 1.27 1.27)
					(thickness 0.15)
				)
				(justify left bottom)
				(hide yes)
			)
		)
		(property "Description" "SMD Multilayer Ceramic Capacitor,  10µF, 10V, 0603, ±10%, X7R"
			(at 53.34 127 0)
			(effects
				(font
					(size 1.27 1.27)
				)
				(hide yes)
			)
		)
		(property "MPN" "GRM188Z71A106KA73D"
			(at 71.12 111.76 0)
			(effects
				(font
					(size 1.27 1.27)
					(thickness 0.15)
				)
				(justify left bottom)
				(hide yes)
			)
		)
		(property "Val" "10u"
			(at 55.118 125.73 90)
			(effects
				(font
					(size 1.27 1.27)
					(thickness 0.15)
				)
				(justify right)
			)
		)
		(property "Voltage" "10V"
			(at 73.66 111.76 0)
			(effects
				(font
					(size 1.27 1.27)
					(thickness 0.15)
				)
				(justify left bottom)
				(hide yes)
			)
		)
		(property "Dielectric" "X7R"
			(at 76.2 111.76 0)
			(effects
				(font
					(size 1.27 1.27)
					(thickness 0.15)
				)
				(justify left bottom)
				(hide yes)
			)
		)
		(property "Manufacturer" "Murata"
			(at 78.74 111.76 0)
			(effects
				(font
					(size 1.27 1.27)
					(thickness 0.15)
				)
				(justify left bottom)
				(hide yes)
			)
		)
		(property "License" "Apache-2.0"
			(at 81.28 111.76 0)
			(effects
				(font
					(size 1.27 1.27)
					(thickness 0.15)
				)
				(justify left bottom)
				(hide yes)
			)
		)
		(property "Author" "Antmicro"
			(at 83.82 111.76 0)
			(effects
				(font
					(size 1.27 1.27)
					(thickness 0.15)
				)
				(justify left bottom)
				(hide yes)
			)
		)
		(pin "1"
		)
		(pin "2"
		)
		(instances
			(project "OCuLink to 10GbE adapter"
				(path ""
					(reference "C139")
					(unit 1)
				)
			)
		)
	)
	(symbol
		(lib_id "antmicropower:GND")
		(at 335.28 115.57 0)
		(unit 1)
		(exclude_from_sim no)
		(in_bom yes)
		(on_board yes)
		(dnp no)
		(property "Reference" "#PWR0181"
			(at 344.17 118.11 0)
			(effects
				(font
					(size 1.27 1.27)
					(thickness 0.15)
				)
				(justify left bottom)
				(hide yes)
			)
		)
		(property "Value" "GND"
			(at 335.28 119.38 0)
			(effects
				(font
					(size 1.27 1.27)
					(thickness 0.15)
				)
			)
		)
		(property "Footprint" ""
			(at 344.17 123.19 0)
			(effects
				(font
					(size 1.27 1.27)
					(thickness 0.15)
				)
				(justify left bottom)
				(hide yes)
			)
		)
		(property "Datasheet" ""
			(at 344.17 128.27 0)
			(effects
				(font
					(size 1.27 1.27)
					(thickness 0.15)
				)
				(justify left bottom)
				(hide yes)
			)
		)
		(property "Description" ""
			(at 335.28 115.57 0)
			(effects
				(font
					(size 1.27 1.27)
				)
				(hide yes)
			)
		)
		(property "Author" "Antmicro"
			(at 344.17 123.19 0)
			(effects
				(font
					(size 1.27 1.27)
					(thickness 0.15)
				)
				(justify left bottom)
				(hide yes)
			)
		)
		(property "License" "Apache-2.0"
			(at 344.17 125.73 0)
			(effects
				(font
					(size 1.27 1.27)
					(thickness 0.15)
				)
				(justify left bottom)
				(hide yes)
			)
		)
		(pin "1"
		)
		(instances
			(project "OCuLink to 10GbE adapter"
				(path ""
					(reference "#PWR0181")
					(unit 1)
				)
			)
		)
	)
	(symbol
		(lib_id "antmicropower:GND")
		(at 80.01 54.61 0)
		(unit 1)
		(exclude_from_sim no)
		(in_bom yes)
		(on_board yes)
		(dnp no)
		(property "Reference" "#PWR0116"
			(at 88.9 57.15 0)
			(effects
				(font
					(size 1.27 1.27)
					(thickness 0.15)
				)
				(justify left bottom)
				(hide yes)
			)
		)
		(property "Value" "GND"
			(at 80.01 58.42 0)
			(effects
				(font
					(size 1.27 1.27)
					(thickness 0.15)
				)
			)
		)
		(property "Footprint" ""
			(at 88.9 62.23 0)
			(effects
				(font
					(size 1.27 1.27)
					(thickness 0.15)
				)
				(justify left bottom)
				(hide yes)
			)
		)
		(property "Datasheet" ""
			(at 88.9 67.31 0)
			(effects
				(font
					(size 1.27 1.27)
					(thickness 0.15)
				)
				(justify left bottom)
				(hide yes)
			)
		)
		(property "Description" ""
			(at 80.01 54.61 0)
			(effects
				(font
					(size 1.27 1.27)
				)
				(hide yes)
			)
		)
		(property "Author" "Antmicro"
			(at 88.9 62.23 0)
			(effects
				(font
					(size 1.27 1.27)
					(thickness 0.15)
				)
				(justify left bottom)
				(hide yes)
			)
		)
		(property "License" "Apache-2.0"
			(at 88.9 64.77 0)
			(effects
				(font
					(size 1.27 1.27)
					(thickness 0.15)
				)
				(justify left bottom)
				(hide yes)
			)
		)
		(pin "1"
		)
		(instances
			(project "OCuLink to 10GbE adapter"
				(path ""
					(reference "#PWR0116")
					(unit 1)
				)
			)
		)
	)
	(symbol
		(lib_id "antmicropower:GND")
		(at 33.02 54.61 0)
		(unit 1)
		(exclude_from_sim no)
		(in_bom yes)
		(on_board yes)
		(dnp no)
		(property "Reference" "#PWR0112"
			(at 41.91 57.15 0)
			(effects
				(font
					(size 1.27 1.27)
					(thickness 0.15)
				)
				(justify left bottom)
				(hide yes)
			)
		)
		(property "Value" "GND"
			(at 33.02 58.42 0)
			(effects
				(font
					(size 1.27 1.27)
					(thickness 0.15)
				)
			)
		)
		(property "Footprint" ""
			(at 41.91 62.23 0)
			(effects
				(font
					(size 1.27 1.27)
					(thickness 0.15)
				)
				(justify left bottom)
				(hide yes)
			)
		)
		(property "Datasheet" ""
			(at 41.91 67.31 0)
			(effects
				(font
					(size 1.27 1.27)
					(thickness 0.15)
				)
				(justify left bottom)
				(hide yes)
			)
		)
		(property "Description" ""
			(at 33.02 54.61 0)
			(effects
				(font
					(size 1.27 1.27)
				)
				(hide yes)
			)
		)
		(property "Author" "Antmicro"
			(at 41.91 62.23 0)
			(effects
				(font
					(size 1.27 1.27)
					(thickness 0.15)
				)
				(justify left bottom)
				(hide yes)
			)
		)
		(property "License" "Apache-2.0"
			(at 41.91 64.77 0)
			(effects
				(font
					(size 1.27 1.27)
					(thickness 0.15)
				)
				(justify left bottom)
				(hide yes)
			)
		)
		(pin "1"
		)
		(instances
			(project "OCuLink to 10GbE adapter"
				(path ""
					(reference "#PWR0112")
					(unit 1)
				)
			)
		)
	)
	(symbol
		(lib_id "antmicropower:+1V0")
		(at 21.59 250.19 0)
		(unit 1)
		(exclude_from_sim no)
		(in_bom yes)
		(on_board yes)
		(dnp no)
		(property "Reference" "#PWR0242"
			(at 21.59 254 0)
			(effects
				(font
					(size 1.27 1.27)
				)
				(hide yes)
			)
		)
		(property "Value" "+1V0"
			(at 21.59 246.126 0)
			(effects
				(font
					(size 1.27 1.27)
				)
			)
		)
		(property "Footprint" ""
			(at 21.59 250.19 0)
			(effects
				(font
					(size 1.27 1.27)
				)
				(hide yes)
			)
		)
		(property "Datasheet" ""
			(at 21.59 250.19 0)
			(effects
				(font
					(size 1.27 1.27)
				)
				(hide yes)
			)
		)
		(property "Description" ""
			(at 21.59 250.19 0)
			(effects
				(font
					(size 1.27 1.27)
				)
				(hide yes)
			)
		)
		(pin "1"
		)
		(instances
			(project "OCuLink to 10GbE adapter"
				(path ""
					(reference "#PWR0242")
					(unit 1)
				)
			)
		)
	)
	(symbol
		(lib_id "antmicroCapacitors0402:C_100n_0402")
		(at 41.91 100.33 90)
		(unit 1)
		(exclude_from_sim no)
		(in_bom yes)
		(on_board yes)
		(dnp no)
		(property "Reference" "C128"
			(at 43.942 96.52 90)
			(effects
				(font
					(size 1.27 1.27)
					(thickness 0.15)
				)
				(justify right)
			)
		)
		(property "Value" "C_100n_0402"
			(at 64.77 85.09 0)
			(effects
				(font
					(size 1.27 1.27)
					(thickness 0.15)
				)
				(justify left bottom)
				(hide yes)
			)
		)
		(property "Footprint" "antmicro-footprints:C_0402_1005Metric"
			(at 67.31 85.09 0)
			(effects
				(font
					(size 1.27 1.27)
					(thickness 0.15)
				)
				(justify left bottom)
				(hide yes)
			)
		)
		(property "Datasheet" "https://www.murata.com/products/productdetail?partno=GRM155R61H104KE14%23"
			(at 69.85 85.09 0)
			(effects
				(font
					(size 1.27 1.27)
					(thickness 0.15)
				)
				(justify left bottom)
				(hide yes)
			)
		)
		(property "Description" "SMD Multilayer Ceramic Capacitor, 0.1 µF, 50 V, 0402 [1005 Metric], ± 10%, X5R, GRM Series"
			(at 41.91 100.33 0)
			(effects
				(font
					(size 1.27 1.27)
				)
				(hide yes)
			)
		)
		(property "MPN" "GRM155R61H104KE14D"
			(at 72.39 85.09 0)
			(effects
				(font
					(size 1.27 1.27)
					(thickness 0.15)
				)
				(justify left bottom)
				(hide yes)
			)
		)
		(property "Val" "100n"
			(at 43.942 99.06 90)
			(effects
				(font
					(size 1.27 1.27)
					(thickness 0.15)
				)
				(justify right)
			)
		)
		(property "Voltage" "50V"
			(at 52.07 85.09 0)
			(effects
				(font
					(size 1.27 1.27)
					(thickness 0.15)
				)
				(justify left bottom)
				(hide yes)
			)
		)
		(property "Dielectric" "X5R"
			(at 54.61 85.09 0)
			(effects
				(font
					(size 1.27 1.27)
					(thickness 0.15)
				)
				(justify left bottom)
				(hide yes)
			)
		)
		(property "Manufacturer" "Murata"
			(at 57.15 85.09 0)
			(effects
				(font
					(size 1.27 1.27)
					(thickness 0.15)
				)
				(justify left bottom)
				(hide yes)
			)
		)
		(property "License" "Apache-2.0"
			(at 59.69 85.09 0)
			(effects
				(font
					(size 1.27 1.27)
					(thickness 0.15)
				)
				(justify left bottom)
				(hide yes)
			)
		)
		(property "Author" "Antmicro"
			(at 62.23 85.09 0)
			(effects
				(font
					(size 1.27 1.27)
					(thickness 0.15)
				)
				(justify left bottom)
				(hide yes)
			)
		)
		(pin "2"
		)
		(pin "1"
		)
		(instances
			(project "OCuLink to 10GbE adapter"
				(path ""
					(reference "C128")
					(unit 1)
				)
			)
		)
	)
	(symbol
		(lib_id "antmicroCapacitors0402:C_1u_25V_0402")
		(at 335.28 52.07 90)
		(unit 1)
		(exclude_from_sim no)
		(in_bom yes)
		(on_board yes)
		(dnp no)
		(property "Reference" "C91"
			(at 337.312 48.26 90)
			(effects
				(font
					(size 1.27 1.27)
					(thickness 0.15)
				)
				(justify right)
			)
		)
		(property "Value" "C_1u_25V_0402"
			(at 345.44 31.75 0)
			(effects
				(font
					(size 1.27 1.27)
					(thickness 0.15)
				)
				(justify left bottom)
				(hide yes)
			)
		)
		(property "Footprint" "antmicro-footprints:C_0402_1005Metric"
			(at 347.98 31.75 0)
			(effects
				(font
					(size 1.27 1.27)
					(thickness 0.15)
				)
				(justify left bottom)
				(hide yes)
			)
		)
		(property "Datasheet" "https://www.murata.com/products/productdetail?partno=GRM155R61E105KE11%23"
			(at 350.52 31.75 0)
			(effects
				(font
					(size 1.27 1.27)
					(thickness 0.15)
				)
				(justify left bottom)
				(hide yes)
			)
		)
		(property "Description" "SMD Multilayer Ceramic Capacitor, 1 µF, 25 V, 0402 [1005 Metric], ± 10%, X5R, GRM Series"
			(at 335.28 52.07 0)
			(effects
				(font
					(size 1.27 1.27)
				)
				(hide yes)
			)
		)
		(property "MPN" "GRM155R61E105KE11J"
			(at 353.06 31.75 0)
			(effects
				(font
					(size 1.27 1.27)
					(thickness 0.15)
				)
				(justify left bottom)
				(hide yes)
			)
		)
		(property "Manufacturer" "Murata"
			(at 355.6 31.75 0)
			(effects
				(font
					(size 1.27 1.27)
					(thickness 0.15)
				)
				(justify left bottom)
				(hide yes)
			)
		)
		(property "License" "Apache-2.0"
			(at 358.14 31.75 0)
			(effects
				(font
					(size 1.27 1.27)
					(thickness 0.15)
				)
				(justify left bottom)
				(hide yes)
			)
		)
		(property "Author" "Antmicro"
			(at 360.68 31.75 0)
			(effects
				(font
					(size 1.27 1.27)
					(thickness 0.15)
				)
				(justify left bottom)
				(hide yes)
			)
		)
		(property "Val" "1u"
			(at 337.312 50.8 90)
			(effects
				(font
					(size 1.27 1.27)
					(thickness 0.15)
				)
				(justify right)
			)
		)
		(property "Voltage" "25V"
			(at 363.22 31.75 0)
			(effects
				(font
					(size 1.27 1.27)
				)
				(justify left bottom)
				(hide yes)
			)
		)
		(property "Dielectric" "X5R"
			(at 365.76 31.75 0)
			(effects
				(font
					(size 1.27 1.27)
				)
				(justify left bottom)
				(hide yes)
			)
		)
		(pin "2"
		)
		(pin "1"
		)
		(instances
			(project "OCuLink to 10GbE adapter"
				(path ""
					(reference "C91")
					(unit 1)
				)
			)
		)
	)
	(symbol
		(lib_id "antmicroCapacitors0402:C_100n_0402")
		(at 41.91 180.34 90)
		(unit 1)
		(exclude_from_sim no)
		(in_bom yes)
		(on_board yes)
		(dnp no)
		(property "Reference" "C171"
			(at 43.942 176.53 90)
			(effects
				(font
					(size 1.27 1.27)
					(thickness 0.15)
				)
				(justify right)
			)
		)
		(property "Value" "C_100n_0402"
			(at 64.77 165.1 0)
			(effects
				(font
					(size 1.27 1.27)
					(thickness 0.15)
				)
				(justify left bottom)
				(hide yes)
			)
		)
		(property "Footprint" "antmicro-footprints:C_0402_1005Metric"
			(at 67.31 165.1 0)
			(effects
				(font
					(size 1.27 1.27)
					(thickness 0.15)
				)
				(justify left bottom)
				(hide yes)
			)
		)
		(property "Datasheet" "https://www.murata.com/products/productdetail?partno=GRM155R61H104KE14%23"
			(at 69.85 165.1 0)
			(effects
				(font
					(size 1.27 1.27)
					(thickness 0.15)
				)
				(justify left bottom)
				(hide yes)
			)
		)
		(property "Description" "SMD Multilayer Ceramic Capacitor, 0.1 µF, 50 V, 0402 [1005 Metric], ± 10%, X5R, GRM Series"
			(at 41.91 180.34 0)
			(effects
				(font
					(size 1.27 1.27)
				)
				(hide yes)
			)
		)
		(property "MPN" "GRM155R61H104KE14D"
			(at 72.39 165.1 0)
			(effects
				(font
					(size 1.27 1.27)
					(thickness 0.15)
				)
				(justify left bottom)
				(hide yes)
			)
		)
		(property "Val" "100n"
			(at 43.942 179.07 90)
			(effects
				(font
					(size 1.27 1.27)
					(thickness 0.15)
				)
				(justify right)
			)
		)
		(property "Voltage" "50V"
			(at 52.07 165.1 0)
			(effects
				(font
					(size 1.27 1.27)
					(thickness 0.15)
				)
				(justify left bottom)
				(hide yes)
			)
		)
		(property "Dielectric" "X5R"
			(at 54.61 165.1 0)
			(effects
				(font
					(size 1.27 1.27)
					(thickness 0.15)
				)
				(justify left bottom)
				(hide yes)
			)
		)
		(property "Manufacturer" "Murata"
			(at 57.15 165.1 0)
			(effects
				(font
					(size 1.27 1.27)
					(thickness 0.15)
				)
				(justify left bottom)
				(hide yes)
			)
		)
		(property "License" "Apache-2.0"
			(at 59.69 165.1 0)
			(effects
				(font
					(size 1.27 1.27)
					(thickness 0.15)
				)
				(justify left bottom)
				(hide yes)
			)
		)
		(property "Author" "Antmicro"
			(at 62.23 165.1 0)
			(effects
				(font
					(size 1.27 1.27)
					(thickness 0.15)
				)
				(justify left bottom)
				(hide yes)
			)
		)
		(pin "2"
		)
		(pin "1"
		)
		(instances
			(project "OCuLink to 10GbE adapter"
				(path ""
					(reference "C171")
					(unit 1)
				)
			)
		)
	)
	(symbol
		(lib_id "antmicroCapacitors0402:C_1u_25V_0402")
		(at 115.57 153.67 90)
		(unit 1)
		(exclude_from_sim no)
		(in_bom yes)
		(on_board yes)
		(dnp no)
		(property "Reference" "C169"
			(at 117.602 149.86 90)
			(effects
				(font
					(size 1.27 1.27)
					(thickness 0.15)
				)
				(justify right)
			)
		)
		(property "Value" "C_1u_25V_0402"
			(at 125.73 133.35 0)
			(effects
				(font
					(size 1.27 1.27)
					(thickness 0.15)
				)
				(justify left bottom)
				(hide yes)
			)
		)
		(property "Footprint" "antmicro-footprints:C_0402_1005Metric"
			(at 128.27 133.35 0)
			(effects
				(font
					(size 1.27 1.27)
					(thickness 0.15)
				)
				(justify left bottom)
				(hide yes)
			)
		)
		(property "Datasheet" "https://www.murata.com/products/productdetail?partno=GRM155R61E105KE11%23"
			(at 130.81 133.35 0)
			(effects
				(font
					(size 1.27 1.27)
					(thickness 0.15)
				)
				(justify left bottom)
				(hide yes)
			)
		)
		(property "Description" "SMD Multilayer Ceramic Capacitor, 1 µF, 25 V, 0402 [1005 Metric], ± 10%, X5R, GRM Series"
			(at 115.57 153.67 0)
			(effects
				(font
					(size 1.27 1.27)
				)
				(hide yes)
			)
		)
		(property "MPN" "GRM155R61E105KE11J"
			(at 133.35 133.35 0)
			(effects
				(font
					(size 1.27 1.27)
					(thickness 0.15)
				)
				(justify left bottom)
				(hide yes)
			)
		)
		(property "Manufacturer" "Murata"
			(at 135.89 133.35 0)
			(effects
				(font
					(size 1.27 1.27)
					(thickness 0.15)
				)
				(justify left bottom)
				(hide yes)
			)
		)
		(property "License" "Apache-2.0"
			(at 138.43 133.35 0)
			(effects
				(font
					(size 1.27 1.27)
					(thickness 0.15)
				)
				(justify left bottom)
				(hide yes)
			)
		)
		(property "Author" "Antmicro"
			(at 140.97 133.35 0)
			(effects
				(font
					(size 1.27 1.27)
					(thickness 0.15)
				)
				(justify left bottom)
				(hide yes)
			)
		)
		(property "Val" "1u"
			(at 117.602 152.4 90)
			(effects
				(font
					(size 1.27 1.27)
					(thickness 0.15)
				)
				(justify right)
			)
		)
		(property "Voltage" "25V"
			(at 143.51 133.35 0)
			(effects
				(font
					(size 1.27 1.27)
				)
				(justify left bottom)
				(hide yes)
			)
		)
		(property "Dielectric" "X5R"
			(at 146.05 133.35 0)
			(effects
				(font
					(size 1.27 1.27)
				)
				(justify left bottom)
				(hide yes)
			)
		)
		(pin "2"
		)
		(pin "1"
		)
		(instances
			(project "OCuLink to 10GbE adapter"
				(path ""
					(reference "C169")
					(unit 1)
				)
			)
		)
	)
	(symbol
		(lib_id "antmicroCapacitors0402:C_1u_25V_0402")
		(at 115.57 207.01 90)
		(unit 1)
		(exclude_from_sim no)
		(in_bom yes)
		(on_board yes)
		(dnp no)
		(property "Reference" "C184"
			(at 117.602 203.2 90)
			(effects
				(font
					(size 1.27 1.27)
					(thickness 0.15)
				)
				(justify right)
			)
		)
		(property "Value" "C_1u_25V_0402"
			(at 125.73 186.69 0)
			(effects
				(font
					(size 1.27 1.27)
					(thickness 0.15)
				)
				(justify left bottom)
				(hide yes)
			)
		)
		(property "Footprint" "antmicro-footprints:C_0402_1005Metric"
			(at 128.27 186.69 0)
			(effects
				(font
					(size 1.27 1.27)
					(thickness 0.15)
				)
				(justify left bottom)
				(hide yes)
			)
		)
		(property "Datasheet" "https://www.murata.com/products/productdetail?partno=GRM155R61E105KE11%23"
			(at 130.81 186.69 0)
			(effects
				(font
					(size 1.27 1.27)
					(thickness 0.15)
				)
				(justify left bottom)
				(hide yes)
			)
		)
		(property "Description" "SMD Multilayer Ceramic Capacitor, 1 µF, 25 V, 0402 [1005 Metric], ± 10%, X5R, GRM Series"
			(at 115.57 207.01 0)
			(effects
				(font
					(size 1.27 1.27)
				)
				(hide yes)
			)
		)
		(property "MPN" "GRM155R61E105KE11J"
			(at 133.35 186.69 0)
			(effects
				(font
					(size 1.27 1.27)
					(thickness 0.15)
				)
				(justify left bottom)
				(hide yes)
			)
		)
		(property "Manufacturer" "Murata"
			(at 135.89 186.69 0)
			(effects
				(font
					(size 1.27 1.27)
					(thickness 0.15)
				)
				(justify left bottom)
				(hide yes)
			)
		)
		(property "License" "Apache-2.0"
			(at 138.43 186.69 0)
			(effects
				(font
					(size 1.27 1.27)
					(thickness 0.15)
				)
				(justify left bottom)
				(hide yes)
			)
		)
		(property "Author" "Antmicro"
			(at 140.97 186.69 0)
			(effects
				(font
					(size 1.27 1.27)
					(thickness 0.15)
				)
				(justify left bottom)
				(hide yes)
			)
		)
		(property "Val" "1u"
			(at 117.602 205.74 90)
			(effects
				(font
					(size 1.27 1.27)
					(thickness 0.15)
				)
				(justify right)
			)
		)
		(property "Voltage" "25V"
			(at 143.51 186.69 0)
			(effects
				(font
					(size 1.27 1.27)
				)
				(justify left bottom)
				(hide yes)
			)
		)
		(property "Dielectric" "X5R"
			(at 146.05 186.69 0)
			(effects
				(font
					(size 1.27 1.27)
				)
				(justify left bottom)
				(hide yes)
			)
		)
		(pin "2"
		)
		(pin "1"
		)
		(instances
			(project "OCuLink to 10GbE adapter"
				(path ""
					(reference "C184")
					(unit 1)
				)
			)
		)
	)
	(symbol
		(lib_id "antmicroCapacitors0402:C_1u_25V_0402")
		(at 97.79 52.07 90)
		(unit 1)
		(exclude_from_sim no)
		(in_bom yes)
		(on_board yes)
		(dnp no)
		(property "Reference" "C84"
			(at 99.822 48.26 90)
			(effects
				(font
					(size 1.27 1.27)
					(thickness 0.15)
				)
				(justify right)
			)
		)
		(property "Value" "C_1u_25V_0402"
			(at 107.95 31.75 0)
			(effects
				(font
					(size 1.27 1.27)
					(thickness 0.15)
				)
				(justify left bottom)
				(hide yes)
			)
		)
		(property "Footprint" "antmicro-footprints:C_0402_1005Metric"
			(at 110.49 31.75 0)
			(effects
				(font
					(size 1.27 1.27)
					(thickness 0.15)
				)
				(justify left bottom)
				(hide yes)
			)
		)
		(property "Datasheet" "https://www.murata.com/products/productdetail?partno=GRM155R61E105KE11%23"
			(at 113.03 31.75 0)
			(effects
				(font
					(size 1.27 1.27)
					(thickness 0.15)
				)
				(justify left bottom)
				(hide yes)
			)
		)
		(property "Description" "SMD Multilayer Ceramic Capacitor, 1 µF, 25 V, 0402 [1005 Metric], ± 10%, X5R, GRM Series"
			(at 97.79 52.07 0)
			(effects
				(font
					(size 1.27 1.27)
				)
				(hide yes)
			)
		)
		(property "MPN" "GRM155R61E105KE11J"
			(at 115.57 31.75 0)
			(effects
				(font
					(size 1.27 1.27)
					(thickness 0.15)
				)
				(justify left bottom)
				(hide yes)
			)
		)
		(property "Manufacturer" "Murata"
			(at 118.11 31.75 0)
			(effects
				(font
					(size 1.27 1.27)
					(thickness 0.15)
				)
				(justify left bottom)
				(hide yes)
			)
		)
		(property "License" "Apache-2.0"
			(at 120.65 31.75 0)
			(effects
				(font
					(size 1.27 1.27)
					(thickness 0.15)
				)
				(justify left bottom)
				(hide yes)
			)
		)
		(property "Author" "Antmicro"
			(at 123.19 31.75 0)
			(effects
				(font
					(size 1.27 1.27)
					(thickness 0.15)
				)
				(justify left bottom)
				(hide yes)
			)
		)
		(property "Val" "1u"
			(at 99.822 50.8 90)
			(effects
				(font
					(size 1.27 1.27)
					(thickness 0.15)
				)
				(justify right)
			)
		)
		(property "Voltage" "25V"
			(at 125.73 31.75 0)
			(effects
				(font
					(size 1.27 1.27)
				)
				(justify left bottom)
				(hide yes)
			)
		)
		(property "Dielectric" "X5R"
			(at 128.27 31.75 0)
			(effects
				(font
					(size 1.27 1.27)
				)
				(justify left bottom)
				(hide yes)
			)
		)
		(pin "2"
		)
		(pin "1"
		)
		(instances
			(project "OCuLink to 10GbE adapter"
				(path ""
					(reference "C84")
					(unit 1)
				)
			)
		)
	)
	(symbol
		(lib_id "antmicroCapacitors0402:C_1u_25V_0402")
		(at 115.57 233.68 90)
		(unit 1)
		(exclude_from_sim no)
		(in_bom yes)
		(on_board yes)
		(dnp no)
		(property "Reference" "C187"
			(at 117.602 229.87 90)
			(effects
				(font
					(size 1.27 1.27)
					(thickness 0.15)
				)
				(justify right)
			)
		)
		(property "Value" "C_1u_25V_0402"
			(at 125.73 213.36 0)
			(effects
				(font
					(size 1.27 1.27)
					(thickness 0.15)
				)
				(justify left bottom)
				(hide yes)
			)
		)
		(property "Footprint" "antmicro-footprints:C_0402_1005Metric"
			(at 128.27 213.36 0)
			(effects
				(font
					(size 1.27 1.27)
					(thickness 0.15)
				)
				(justify left bottom)
				(hide yes)
			)
		)
		(property "Datasheet" "https://www.murata.com/products/productdetail?partno=GRM155R61E105KE11%23"
			(at 130.81 213.36 0)
			(effects
				(font
					(size 1.27 1.27)
					(thickness 0.15)
				)
				(justify left bottom)
				(hide yes)
			)
		)
		(property "Description" "SMD Multilayer Ceramic Capacitor, 1 µF, 25 V, 0402 [1005 Metric], ± 10%, X5R, GRM Series"
			(at 115.57 233.68 0)
			(effects
				(font
					(size 1.27 1.27)
				)
				(hide yes)
			)
		)
		(property "MPN" "GRM155R61E105KE11J"
			(at 133.35 213.36 0)
			(effects
				(font
					(size 1.27 1.27)
					(thickness 0.15)
				)
				(justify left bottom)
				(hide yes)
			)
		)
		(property "Manufacturer" "Murata"
			(at 135.89 213.36 0)
			(effects
				(font
					(size 1.27 1.27)
					(thickness 0.15)
				)
				(justify left bottom)
				(hide yes)
			)
		)
		(property "License" "Apache-2.0"
			(at 138.43 213.36 0)
			(effects
				(font
					(size 1.27 1.27)
					(thickness 0.15)
				)
				(justify left bottom)
				(hide yes)
			)
		)
		(property "Author" "Antmicro"
			(at 140.97 213.36 0)
			(effects
				(font
					(size 1.27 1.27)
					(thickness 0.15)
				)
				(justify left bottom)
				(hide yes)
			)
		)
		(property "Val" "1u"
			(at 117.602 232.41 90)
			(effects
				(font
					(size 1.27 1.27)
					(thickness 0.15)
				)
				(justify right)
			)
		)
		(property "Voltage" "25V"
			(at 143.51 213.36 0)
			(effects
				(font
					(size 1.27 1.27)
				)
				(justify left bottom)
				(hide yes)
			)
		)
		(property "Dielectric" "X5R"
			(at 146.05 213.36 0)
			(effects
				(font
					(size 1.27 1.27)
				)
				(justify left bottom)
				(hide yes)
			)
		)
		(pin "2"
		)
		(pin "1"
		)
		(instances
			(project "OCuLink to 10GbE adapter"
				(path ""
					(reference "C187")
					(unit 1)
				)
			)
		)
	)
	(symbol
		(lib_id "antmicropower:GND")
		(at 353.06 133.35 0)
		(unit 1)
		(exclude_from_sim no)
		(in_bom yes)
		(on_board yes)
		(dnp no)
		(property "Reference" "#PWR0200"
			(at 361.95 135.89 0)
			(effects
				(font
					(size 1.27 1.27)
					(thickness 0.15)
				)
				(justify left bottom)
				(hide yes)
			)
		)
		(property "Value" "GND"
			(at 353.06 137.16 0)
			(effects
				(font
					(size 1.27 1.27)
					(thickness 0.15)
				)
			)
		)
		(property "Footprint" ""
			(at 361.95 140.97 0)
			(effects
				(font
					(size 1.27 1.27)
					(thickness 0.15)
				)
				(justify left bottom)
				(hide yes)
			)
		)
		(property "Datasheet" ""
			(at 361.95 146.05 0)
			(effects
				(font
					(size 1.27 1.27)
					(thickness 0.15)
				)
				(justify left bottom)
				(hide yes)
			)
		)
		(property "Description" ""
			(at 353.06 133.35 0)
			(effects
				(font
					(size 1.27 1.27)
				)
				(hide yes)
			)
		)
		(property "Author" "Antmicro"
			(at 361.95 140.97 0)
			(effects
				(font
					(size 1.27 1.27)
					(thickness 0.15)
				)
				(justify left bottom)
				(hide yes)
			)
		)
		(property "License" "Apache-2.0"
			(at 361.95 143.51 0)
			(effects
				(font
					(size 1.27 1.27)
					(thickness 0.15)
				)
				(justify left bottom)
				(hide yes)
			)
		)
		(pin "1"
		)
		(instances
			(project "OCuLink to 10GbE adapter"
				(path ""
					(reference "#PWR0200")
					(unit 1)
				)
			)
		)
	)
	(symbol
		(lib_id "antmicroCapacitors0402:C_1u_25V_0402")
		(at 308.61 52.07 90)
		(unit 1)
		(exclude_from_sim no)
		(in_bom yes)
		(on_board yes)
		(dnp no)
		(property "Reference" "C88"
			(at 310.642 48.26 90)
			(effects
				(font
					(size 1.27 1.27)
					(thickness 0.15)
				)
				(justify right)
			)
		)
		(property "Value" "C_1u_25V_0402"
			(at 318.77 31.75 0)
			(effects
				(font
					(size 1.27 1.27)
					(thickness 0.15)
				)
				(justify left bottom)
				(hide yes)
			)
		)
		(property "Footprint" "antmicro-footprints:C_0402_1005Metric"
			(at 321.31 31.75 0)
			(effects
				(font
					(size 1.27 1.27)
					(thickness 0.15)
				)
				(justify left bottom)
				(hide yes)
			)
		)
		(property "Datasheet" "https://www.murata.com/products/productdetail?partno=GRM155R61E105KE11%23"
			(at 323.85 31.75 0)
			(effects
				(font
					(size 1.27 1.27)
					(thickness 0.15)
				)
				(justify left bottom)
				(hide yes)
			)
		)
		(property "Description" "SMD Multilayer Ceramic Capacitor, 1 µF, 25 V, 0402 [1005 Metric], ± 10%, X5R, GRM Series"
			(at 308.61 52.07 0)
			(effects
				(font
					(size 1.27 1.27)
				)
				(hide yes)
			)
		)
		(property "MPN" "GRM155R61E105KE11J"
			(at 326.39 31.75 0)
			(effects
				(font
					(size 1.27 1.27)
					(thickness 0.15)
				)
				(justify left bottom)
				(hide yes)
			)
		)
		(property "Manufacturer" "Murata"
			(at 328.93 31.75 0)
			(effects
				(font
					(size 1.27 1.27)
					(thickness 0.15)
				)
				(justify left bottom)
				(hide yes)
			)
		)
		(property "License" "Apache-2.0"
			(at 331.47 31.75 0)
			(effects
				(font
					(size 1.27 1.27)
					(thickness 0.15)
				)
				(justify left bottom)
				(hide yes)
			)
		)
		(property "Author" "Antmicro"
			(at 334.01 31.75 0)
			(effects
				(font
					(size 1.27 1.27)
					(thickness 0.15)
				)
				(justify left bottom)
				(hide yes)
			)
		)
		(property "Val" "1u"
			(at 310.642 50.8 90)
			(effects
				(font
					(size 1.27 1.27)
					(thickness 0.15)
				)
				(justify right)
			)
		)
		(property "Voltage" "25V"
			(at 336.55 31.75 0)
			(effects
				(font
					(size 1.27 1.27)
				)
				(justify left bottom)
				(hide yes)
			)
		)
		(property "Dielectric" "X5R"
			(at 339.09 31.75 0)
			(effects
				(font
					(size 1.27 1.27)
				)
				(justify left bottom)
				(hide yes)
			)
		)
		(pin "2"
		)
		(pin "1"
		)
		(instances
			(project "OCuLink to 10GbE adapter"
				(path ""
					(reference "C88")
					(unit 1)
				)
			)
		)
	)
	(symbol
		(lib_id "antmicroCapacitors0402:C_1u_25V_0402")
		(at 54.61 260.35 90)
		(unit 1)
		(exclude_from_sim no)
		(in_bom yes)
		(on_board yes)
		(dnp no)
		(property "Reference" "C189"
			(at 56.642 256.54 90)
			(effects
				(font
					(size 1.27 1.27)
					(thickness 0.15)
				)
				(justify right)
			)
		)
		(property "Value" "C_1u_25V_0402"
			(at 64.77 240.03 0)
			(effects
				(font
					(size 1.27 1.27)
					(thickness 0.15)
				)
				(justify left bottom)
				(hide yes)
			)
		)
		(property "Footprint" "antmicro-footprints:C_0402_1005Metric"
			(at 67.31 240.03 0)
			(effects
				(font
					(size 1.27 1.27)
					(thickness 0.15)
				)
				(justify left bottom)
				(hide yes)
			)
		)
		(property "Datasheet" "https://www.murata.com/products/productdetail?partno=GRM155R61E105KE11%23"
			(at 69.85 240.03 0)
			(effects
				(font
					(size 1.27 1.27)
					(thickness 0.15)
				)
				(justify left bottom)
				(hide yes)
			)
		)
		(property "Description" "SMD Multilayer Ceramic Capacitor, 1 µF, 25 V, 0402 [1005 Metric], ± 10%, X5R, GRM Series"
			(at 54.61 260.35 0)
			(effects
				(font
					(size 1.27 1.27)
				)
				(hide yes)
			)
		)
		(property "MPN" "GRM155R61E105KE11J"
			(at 72.39 240.03 0)
			(effects
				(font
					(size 1.27 1.27)
					(thickness 0.15)
				)
				(justify left bottom)
				(hide yes)
			)
		)
		(property "Manufacturer" "Murata"
			(at 74.93 240.03 0)
			(effects
				(font
					(size 1.27 1.27)
					(thickness 0.15)
				)
				(justify left bottom)
				(hide yes)
			)
		)
		(property "License" "Apache-2.0"
			(at 77.47 240.03 0)
			(effects
				(font
					(size 1.27 1.27)
					(thickness 0.15)
				)
				(justify left bottom)
				(hide yes)
			)
		)
		(property "Author" "Antmicro"
			(at 80.01 240.03 0)
			(effects
				(font
					(size 1.27 1.27)
					(thickness 0.15)
				)
				(justify left bottom)
				(hide yes)
			)
		)
		(property "Val" "1u"
			(at 56.642 259.08 90)
			(effects
				(font
					(size 1.27 1.27)
					(thickness 0.15)
				)
				(justify right)
			)
		)
		(property "Voltage" "25V"
			(at 82.55 240.03 0)
			(effects
				(font
					(size 1.27 1.27)
				)
				(justify left bottom)
				(hide yes)
			)
		)
		(property "Dielectric" "X5R"
			(at 85.09 240.03 0)
			(effects
				(font
					(size 1.27 1.27)
				)
				(justify left bottom)
				(hide yes)
			)
		)
		(pin "2"
		)
		(pin "1"
		)
		(instances
			(project "OCuLink to 10GbE adapter"
				(path ""
					(reference "C189")
					(unit 1)
				)
			)
		)
	)
	(symbol
		(lib_id "antmicroCapacitors0402:C_1u_25V_0402")
		(at 106.68 127 90)
		(unit 1)
		(exclude_from_sim no)
		(in_bom yes)
		(on_board yes)
		(dnp no)
		(property "Reference" "C144"
			(at 108.458 123.19 90)
			(effects
				(font
					(size 1.27 1.27)
					(thickness 0.15)
				)
				(justify right)
			)
		)
		(property "Value" "C_1u_25V_0402"
			(at 116.84 106.68 0)
			(effects
				(font
					(size 1.27 1.27)
					(thickness 0.15)
				)
				(justify left bottom)
				(hide yes)
			)
		)
		(property "Footprint" "antmicro-footprints:C_0402_1005Metric"
			(at 119.38 106.68 0)
			(effects
				(font
					(size 1.27 1.27)
					(thickness 0.15)
				)
				(justify left bottom)
				(hide yes)
			)
		)
		(property "Datasheet" "https://www.murata.com/products/productdetail?partno=GRM155R61E105KE11%23"
			(at 121.92 106.68 0)
			(effects
				(font
					(size 1.27 1.27)
					(thickness 0.15)
				)
				(justify left bottom)
				(hide yes)
			)
		)
		(property "Description" "SMD Multilayer Ceramic Capacitor, 1 µF, 25 V, 0402 [1005 Metric], ± 10%, X5R, GRM Series"
			(at 106.68 127 0)
			(effects
				(font
					(size 1.27 1.27)
				)
				(hide yes)
			)
		)
		(property "MPN" "GRM155R61E105KE11J"
			(at 124.46 106.68 0)
			(effects
				(font
					(size 1.27 1.27)
					(thickness 0.15)
				)
				(justify left bottom)
				(hide yes)
			)
		)
		(property "Manufacturer" "Murata"
			(at 127 106.68 0)
			(effects
				(font
					(size 1.27 1.27)
					(thickness 0.15)
				)
				(justify left bottom)
				(hide yes)
			)
		)
		(property "License" "Apache-2.0"
			(at 129.54 106.68 0)
			(effects
				(font
					(size 1.27 1.27)
					(thickness 0.15)
				)
				(justify left bottom)
				(hide yes)
			)
		)
		(property "Author" "Antmicro"
			(at 132.08 106.68 0)
			(effects
				(font
					(size 1.27 1.27)
					(thickness 0.15)
				)
				(justify left bottom)
				(hide yes)
			)
		)
		(property "Val" "1u"
			(at 108.458 125.73 90)
			(effects
				(font
					(size 1.27 1.27)
					(thickness 0.15)
				)
				(justify right)
			)
		)
		(property "Voltage" "25V"
			(at 134.62 106.68 0)
			(effects
				(font
					(size 1.27 1.27)
				)
				(justify left bottom)
				(hide yes)
			)
		)
		(property "Dielectric" "X5R"
			(at 137.16 106.68 0)
			(effects
				(font
					(size 1.27 1.27)
				)
				(justify left bottom)
				(hide yes)
			)
		)
		(pin "2"
		)
		(pin "1"
		)
		(instances
			(project "OCuLink to 10GbE adapter"
				(path ""
					(reference "C144")
					(unit 1)
				)
			)
		)
	)
	(symbol
		(lib_id "antmicropower:GND")
		(at 317.5 76.2 0)
		(unit 1)
		(exclude_from_sim no)
		(in_bom yes)
		(on_board yes)
		(dnp no)
		(property "Reference" "#PWR0141"
			(at 326.39 78.74 0)
			(effects
				(font
					(size 1.27 1.27)
					(thickness 0.15)
				)
				(justify left bottom)
				(hide yes)
			)
		)
		(property "Value" "GND"
			(at 317.5 80.01 0)
			(effects
				(font
					(size 1.27 1.27)
					(thickness 0.15)
				)
			)
		)
		(property "Footprint" ""
			(at 326.39 83.82 0)
			(effects
				(font
					(size 1.27 1.27)
					(thickness 0.15)
				)
				(justify left bottom)
				(hide yes)
			)
		)
		(property "Datasheet" ""
			(at 326.39 88.9 0)
			(effects
				(font
					(size 1.27 1.27)
					(thickness 0.15)
				)
				(justify left bottom)
				(hide yes)
			)
		)
		(property "Description" ""
			(at 317.5 76.2 0)
			(effects
				(font
					(size 1.27 1.27)
				)
				(hide yes)
			)
		)
		(property "Author" "Antmicro"
			(at 326.39 83.82 0)
			(effects
				(font
					(size 1.27 1.27)
					(thickness 0.15)
				)
				(justify left bottom)
				(hide yes)
			)
		)
		(property "License" "Apache-2.0"
			(at 326.39 86.36 0)
			(effects
				(font
					(size 1.27 1.27)
					(thickness 0.15)
				)
				(justify left bottom)
				(hide yes)
			)
		)
		(pin "1"
		)
		(instances
			(project "OCuLink to 10GbE adapter"
				(path ""
					(reference "#PWR0141")
					(unit 1)
				)
			)
		)
	)
	(symbol
		(lib_id "antmicropower:VDD")
		(at 146.05 78.74 0)
		(unit 1)
		(exclude_from_sim no)
		(in_bom yes)
		(on_board yes)
		(dnp no)
		(property "Reference" "#PWR0152"
			(at 146.05 82.55 0)
			(effects
				(font
					(size 1.27 1.27)
				)
				(hide yes)
			)
		)
		(property "Value" "XFI_PVDD"
			(at 146.05 74.93 0)
			(effects
				(font
					(size 1.27 1.27)
				)
			)
		)
		(property "Footprint" ""
			(at 146.05 78.74 0)
			(effects
				(font
					(size 1.27 1.27)
				)
				(hide yes)
			)
		)
		(property "Datasheet" ""
			(at 146.05 78.74 0)
			(effects
				(font
					(size 1.27 1.27)
				)
				(hide yes)
			)
		)
		(property "Description" ""
			(at 146.05 78.74 0)
			(effects
				(font
					(size 1.27 1.27)
				)
				(hide yes)
			)
		)
		(pin "1"
		)
		(instances
			(project "OCuLink to 10GbE adapter"
				(path ""
					(reference "#PWR0152")
					(unit 1)
				)
			)
		)
	)
	(symbol
		(lib_id "antmicropower:GND")
		(at 370.84 76.2 0)
		(unit 1)
		(exclude_from_sim no)
		(in_bom yes)
		(on_board yes)
		(dnp no)
		(property "Reference" "#PWR0147"
			(at 379.73 78.74 0)
			(effects
				(font
					(size 1.27 1.27)
					(thickness 0.15)
				)
				(justify left bottom)
				(hide yes)
			)
		)
		(property "Value" "GND"
			(at 370.84 80.01 0)
			(effects
				(font
					(size 1.27 1.27)
					(thickness 0.15)
				)
			)
		)
		(property "Footprint" ""
			(at 379.73 83.82 0)
			(effects
				(font
					(size 1.27 1.27)
					(thickness 0.15)
				)
				(justify left bottom)
				(hide yes)
			)
		)
		(property "Datasheet" ""
			(at 379.73 88.9 0)
			(effects
				(font
					(size 1.27 1.27)
					(thickness 0.15)
				)
				(justify left bottom)
				(hide yes)
			)
		)
		(property "Description" ""
			(at 370.84 76.2 0)
			(effects
				(font
					(size 1.27 1.27)
				)
				(hide yes)
			)
		)
		(property "Author" "Antmicro"
			(at 379.73 83.82 0)
			(effects
				(font
					(size 1.27 1.27)
					(thickness 0.15)
				)
				(justify left bottom)
				(hide yes)
			)
		)
		(property "License" "Apache-2.0"
			(at 379.73 86.36 0)
			(effects
				(font
					(size 1.27 1.27)
					(thickness 0.15)
				)
				(justify left bottom)
				(hide yes)
			)
		)
		(pin "1"
		)
		(instances
			(project "OCuLink to 10GbE adapter"
				(path ""
					(reference "#PWR0147")
					(unit 1)
				)
			)
		)
	)
	(symbol
		(lib_id "antmicropower:GND")
		(at 53.34 76.2 0)
		(unit 1)
		(exclude_from_sim no)
		(in_bom yes)
		(on_board yes)
		(dnp no)
		(property "Reference" "#PWR0133"
			(at 62.23 78.74 0)
			(effects
				(font
					(size 1.27 1.27)
					(thickness 0.15)
				)
				(justify left bottom)
				(hide yes)
			)
		)
		(property "Value" "GND"
			(at 53.34 80.01 0)
			(effects
				(font
					(size 1.27 1.27)
					(thickness 0.15)
				)
			)
		)
		(property "Footprint" ""
			(at 62.23 83.82 0)
			(effects
				(font
					(size 1.27 1.27)
					(thickness 0.15)
				)
				(justify left bottom)
				(hide yes)
			)
		)
		(property "Datasheet" ""
			(at 62.23 88.9 0)
			(effects
				(font
					(size 1.27 1.27)
					(thickness 0.15)
				)
				(justify left bottom)
				(hide yes)
			)
		)
		(property "Description" ""
			(at 53.34 76.2 0)
			(effects
				(font
					(size 1.27 1.27)
				)
				(hide yes)
			)
		)
		(property "Author" "Antmicro"
			(at 62.23 83.82 0)
			(effects
				(font
					(size 1.27 1.27)
					(thickness 0.15)
				)
				(justify left bottom)
				(hide yes)
			)
		)
		(property "License" "Apache-2.0"
			(at 62.23 86.36 0)
			(effects
				(font
					(size 1.27 1.27)
					(thickness 0.15)
				)
				(justify left bottom)
				(hide yes)
			)
		)
		(pin "1"
		)
		(instances
			(project "OCuLink to 10GbE adapter"
				(path ""
					(reference "#PWR0133")
					(unit 1)
				)
			)
		)
	)
	(symbol
		(lib_id "antmicroCapacitors0402:C_100n_0402")
		(at 39.37 207.01 90)
		(unit 1)
		(exclude_from_sim no)
		(in_bom yes)
		(on_board yes)
		(dnp no)
		(property "Reference" "C179"
			(at 41.402 203.2 90)
			(effects
				(font
					(size 1.27 1.27)
					(thickness 0.15)
				)
				(justify right)
			)
		)
		(property "Value" "C_100n_0402"
			(at 62.23 191.77 0)
			(effects
				(font
					(size 1.27 1.27)
					(thickness 0.15)
				)
				(justify left bottom)
				(hide yes)
			)
		)
		(property "Footprint" "antmicro-footprints:C_0402_1005Metric"
			(at 64.77 191.77 0)
			(effects
				(font
					(size 1.27 1.27)
					(thickness 0.15)
				)
				(justify left bottom)
				(hide yes)
			)
		)
		(property "Datasheet" "https://www.murata.com/products/productdetail?partno=GRM155R61H104KE14%23"
			(at 67.31 191.77 0)
			(effects
				(font
					(size 1.27 1.27)
					(thickness 0.15)
				)
				(justify left bottom)
				(hide yes)
			)
		)
		(property "Description" "SMD Multilayer Ceramic Capacitor, 0.1 µF, 50 V, 0402 [1005 Metric], ± 10%, X5R, GRM Series"
			(at 39.37 207.01 0)
			(effects
				(font
					(size 1.27 1.27)
				)
				(hide yes)
			)
		)
		(property "MPN" "GRM155R61H104KE14D"
			(at 69.85 191.77 0)
			(effects
				(font
					(size 1.27 1.27)
					(thickness 0.15)
				)
				(justify left bottom)
				(hide yes)
			)
		)
		(property "Val" "100n"
			(at 41.402 205.74 90)
			(effects
				(font
					(size 1.27 1.27)
					(thickness 0.15)
				)
				(justify right)
			)
		)
		(property "Voltage" "50V"
			(at 49.53 191.77 0)
			(effects
				(font
					(size 1.27 1.27)
					(thickness 0.15)
				)
				(justify left bottom)
				(hide yes)
			)
		)
		(property "Dielectric" "X5R"
			(at 52.07 191.77 0)
			(effects
				(font
					(size 1.27 1.27)
					(thickness 0.15)
				)
				(justify left bottom)
				(hide yes)
			)
		)
		(property "Manufacturer" "Murata"
			(at 54.61 191.77 0)
			(effects
				(font
					(size 1.27 1.27)
					(thickness 0.15)
				)
				(justify left bottom)
				(hide yes)
			)
		)
		(property "License" "Apache-2.0"
			(at 57.15 191.77 0)
			(effects
				(font
					(size 1.27 1.27)
					(thickness 0.15)
				)
				(justify left bottom)
				(hide yes)
			)
		)
		(property "Author" "Antmicro"
			(at 59.69 191.77 0)
			(effects
				(font
					(size 1.27 1.27)
					(thickness 0.15)
				)
				(justify left bottom)
				(hide yes)
			)
		)
		(pin "2"
		)
		(pin "1"
		)
		(instances
			(project "OCuLink to 10GbE adapter"
				(path ""
					(reference "C179")
					(unit 1)
				)
			)
		)
	)
	(symbol
		(lib_id "antmicropower:GND")
		(at 344.17 76.2 0)
		(unit 1)
		(exclude_from_sim no)
		(in_bom yes)
		(on_board yes)
		(dnp no)
		(property "Reference" "#PWR0144"
			(at 353.06 78.74 0)
			(effects
				(font
					(size 1.27 1.27)
					(thickness 0.15)
				)
				(justify left bottom)
				(hide yes)
			)
		)
		(property "Value" "GND"
			(at 344.17 80.01 0)
			(effects
				(font
					(size 1.27 1.27)
					(thickness 0.15)
				)
			)
		)
		(property "Footprint" ""
			(at 353.06 83.82 0)
			(effects
				(font
					(size 1.27 1.27)
					(thickness 0.15)
				)
				(justify left bottom)
				(hide yes)
			)
		)
		(property "Datasheet" ""
			(at 353.06 88.9 0)
			(effects
				(font
					(size 1.27 1.27)
					(thickness 0.15)
				)
				(justify left bottom)
				(hide yes)
			)
		)
		(property "Description" ""
			(at 344.17 76.2 0)
			(effects
				(font
					(size 1.27 1.27)
				)
				(hide yes)
			)
		)
		(property "Author" "Antmicro"
			(at 353.06 83.82 0)
			(effects
				(font
					(size 1.27 1.27)
					(thickness 0.15)
				)
				(justify left bottom)
				(hide yes)
			)
		)
		(property "License" "Apache-2.0"
			(at 353.06 86.36 0)
			(effects
				(font
					(size 1.27 1.27)
					(thickness 0.15)
				)
				(justify left bottom)
				(hide yes)
			)
		)
		(pin "1"
		)
		(instances
			(project "OCuLink to 10GbE adapter"
				(path ""
					(reference "#PWR0144")
					(unit 1)
				)
			)
		)
	)
	(symbol
		(lib_id "antmicropower:GND")
		(at 326.39 115.57 0)
		(unit 1)
		(exclude_from_sim no)
		(in_bom yes)
		(on_board yes)
		(dnp no)
		(property "Reference" "#PWR0180"
			(at 335.28 118.11 0)
			(effects
				(font
					(size 1.27 1.27)
					(thickness 0.15)
				)
				(justify left bottom)
				(hide yes)
			)
		)
		(property "Value" "GND"
			(at 326.39 119.38 0)
			(effects
				(font
					(size 1.27 1.27)
					(thickness 0.15)
				)
			)
		)
		(property "Footprint" ""
			(at 335.28 123.19 0)
			(effects
				(font
					(size 1.27 1.27)
					(thickness 0.15)
				)
				(justify left bottom)
				(hide yes)
			)
		)
		(property "Datasheet" ""
			(at 335.28 128.27 0)
			(effects
				(font
					(size 1.27 1.27)
					(thickness 0.15)
				)
				(justify left bottom)
				(hide yes)
			)
		)
		(property "Description" ""
			(at 326.39 115.57 0)
			(effects
				(font
					(size 1.27 1.27)
				)
				(hide yes)
			)
		)
		(property "Author" "Antmicro"
			(at 335.28 123.19 0)
			(effects
				(font
					(size 1.27 1.27)
					(thickness 0.15)
				)
				(justify left bottom)
				(hide yes)
			)
		)
		(property "License" "Apache-2.0"
			(at 335.28 125.73 0)
			(effects
				(font
					(size 1.27 1.27)
					(thickness 0.15)
				)
				(justify left bottom)
				(hide yes)
			)
		)
		(pin "1"
		)
		(instances
			(project "OCuLink to 10GbE adapter"
				(path ""
					(reference "#PWR0180")
					(unit 1)
				)
			)
		)
	)
	(symbol
		(lib_id "antmicropower:GND")
		(at 39.37 209.55 0)
		(unit 1)
		(exclude_from_sim no)
		(in_bom yes)
		(on_board yes)
		(dnp no)
		(property "Reference" "#PWR0232"
			(at 48.26 212.09 0)
			(effects
				(font
					(size 1.27 1.27)
					(thickness 0.15)
				)
				(justify left bottom)
				(hide yes)
			)
		)
		(property "Value" "GND"
			(at 39.37 213.36 0)
			(effects
				(font
					(size 1.27 1.27)
					(thickness 0.15)
				)
			)
		)
		(property "Footprint" ""
			(at 48.26 217.17 0)
			(effects
				(font
					(size 1.27 1.27)
					(thickness 0.15)
				)
				(justify left bottom)
				(hide yes)
			)
		)
		(property "Datasheet" ""
			(at 48.26 222.25 0)
			(effects
				(font
					(size 1.27 1.27)
					(thickness 0.15)
				)
				(justify left bottom)
				(hide yes)
			)
		)
		(property "Description" ""
			(at 39.37 209.55 0)
			(effects
				(font
					(size 1.27 1.27)
				)
				(hide yes)
			)
		)
		(property "Author" "Antmicro"
			(at 48.26 217.17 0)
			(effects
				(font
					(size 1.27 1.27)
					(thickness 0.15)
				)
				(justify left bottom)
				(hide yes)
			)
		)
		(property "License" "Apache-2.0"
			(at 48.26 219.71 0)
			(effects
				(font
					(size 1.27 1.27)
					(thickness 0.15)
				)
				(justify left bottom)
				(hide yes)
			)
		)
		(pin "1"
		)
		(instances
			(project "OCuLink to 10GbE adapter"
				(path ""
					(reference "#PWR0232")
					(unit 1)
				)
			)
		)
	)
	(symbol
		(lib_id "antmicropower:GND")
		(at 379.73 133.35 0)
		(unit 1)
		(exclude_from_sim no)
		(in_bom yes)
		(on_board yes)
		(dnp no)
		(property "Reference" "#PWR0203"
			(at 388.62 135.89 0)
			(effects
				(font
					(size 1.27 1.27)
					(thickness 0.15)
				)
				(justify left bottom)
				(hide yes)
			)
		)
		(property "Value" "GND"
			(at 379.73 137.16 0)
			(effects
				(font
					(size 1.27 1.27)
					(thickness 0.15)
				)
			)
		)
		(property "Footprint" ""
			(at 388.62 140.97 0)
			(effects
				(font
					(size 1.27 1.27)
					(thickness 0.15)
				)
				(justify left bottom)
				(hide yes)
			)
		)
		(property "Datasheet" ""
			(at 388.62 146.05 0)
			(effects
				(font
					(size 1.27 1.27)
					(thickness 0.15)
				)
				(justify left bottom)
				(hide yes)
			)
		)
		(property "Description" ""
			(at 379.73 133.35 0)
			(effects
				(font
					(size 1.27 1.27)
				)
				(hide yes)
			)
		)
		(property "Author" "Antmicro"
			(at 388.62 140.97 0)
			(effects
				(font
					(size 1.27 1.27)
					(thickness 0.15)
				)
				(justify left bottom)
				(hide yes)
			)
		)
		(property "License" "Apache-2.0"
			(at 388.62 143.51 0)
			(effects
				(font
					(size 1.27 1.27)
					(thickness 0.15)
				)
				(justify left bottom)
				(hide yes)
			)
		)
		(pin "1"
		)
		(instances
			(project "OCuLink to 10GbE adapter"
				(path ""
					(reference "#PWR0203")
					(unit 1)
				)
			)
		)
	)
	(symbol
		(lib_id "antmicropower:GND")
		(at 361.95 93.98 0)
		(unit 1)
		(exclude_from_sim no)
		(in_bom yes)
		(on_board yes)
		(dnp no)
		(property "Reference" "#PWR0170"
			(at 370.84 96.52 0)
			(effects
				(font
					(size 1.27 1.27)
					(thickness 0.15)
				)
				(justify left bottom)
				(hide yes)
			)
		)
		(property "Value" "GND"
			(at 361.95 97.79 0)
			(effects
				(font
					(size 1.27 1.27)
					(thickness 0.15)
				)
			)
		)
		(property "Footprint" ""
			(at 370.84 101.6 0)
			(effects
				(font
					(size 1.27 1.27)
					(thickness 0.15)
				)
				(justify left bottom)
				(hide yes)
			)
		)
		(property "Datasheet" ""
			(at 370.84 106.68 0)
			(effects
				(font
					(size 1.27 1.27)
					(thickness 0.15)
				)
				(justify left bottom)
				(hide yes)
			)
		)
		(property "Description" ""
			(at 361.95 93.98 0)
			(effects
				(font
					(size 1.27 1.27)
				)
				(hide yes)
			)
		)
		(property "Author" "Antmicro"
			(at 370.84 101.6 0)
			(effects
				(font
					(size 1.27 1.27)
					(thickness 0.15)
				)
				(justify left bottom)
				(hide yes)
			)
		)
		(property "License" "Apache-2.0"
			(at 370.84 104.14 0)
			(effects
				(font
					(size 1.27 1.27)
					(thickness 0.15)
				)
				(justify left bottom)
				(hide yes)
			)
		)
		(pin "1"
		)
		(instances
			(project "OCuLink to 10GbE adapter"
				(path ""
					(reference "#PWR0170")
					(unit 1)
				)
			)
		)
	)
	(symbol
		(lib_id "antmicroCapacitors0402:C_1u_25V_0402")
		(at 88.9 73.66 90)
		(unit 1)
		(exclude_from_sim no)
		(in_bom yes)
		(on_board yes)
		(dnp no)
		(property "Reference" "C101"
			(at 90.932 69.85 90)
			(effects
				(font
					(size 1.27 1.27)
					(thickness 0.15)
				)
				(justify right)
			)
		)
		(property "Value" "C_1u_25V_0402"
			(at 99.06 53.34 0)
			(effects
				(font
					(size 1.27 1.27)
					(thickness 0.15)
				)
				(justify left bottom)
				(hide yes)
			)
		)
		(property "Footprint" "antmicro-footprints:C_0402_1005Metric"
			(at 101.6 53.34 0)
			(effects
				(font
					(size 1.27 1.27)
					(thickness 0.15)
				)
				(justify left bottom)
				(hide yes)
			)
		)
		(property "Datasheet" "https://www.murata.com/products/productdetail?partno=GRM155R61E105KE11%23"
			(at 104.14 53.34 0)
			(effects
				(font
					(size 1.27 1.27)
					(thickness 0.15)
				)
				(justify left bottom)
				(hide yes)
			)
		)
		(property "Description" "SMD Multilayer Ceramic Capacitor, 1 µF, 25 V, 0402 [1005 Metric], ± 10%, X5R, GRM Series"
			(at 88.9 73.66 0)
			(effects
				(font
					(size 1.27 1.27)
				)
				(hide yes)
			)
		)
		(property "MPN" "GRM155R61E105KE11J"
			(at 106.68 53.34 0)
			(effects
				(font
					(size 1.27 1.27)
					(thickness 0.15)
				)
				(justify left bottom)
				(hide yes)
			)
		)
		(property "Manufacturer" "Murata"
			(at 109.22 53.34 0)
			(effects
				(font
					(size 1.27 1.27)
					(thickness 0.15)
				)
				(justify left bottom)
				(hide yes)
			)
		)
		(property "License" "Apache-2.0"
			(at 111.76 53.34 0)
			(effects
				(font
					(size 1.27 1.27)
					(thickness 0.15)
				)
				(justify left bottom)
				(hide yes)
			)
		)
		(property "Author" "Antmicro"
			(at 114.3 53.34 0)
			(effects
				(font
					(size 1.27 1.27)
					(thickness 0.15)
				)
				(justify left bottom)
				(hide yes)
			)
		)
		(property "Val" "1u"
			(at 90.932 72.39 90)
			(effects
				(font
					(size 1.27 1.27)
					(thickness 0.15)
				)
				(justify right)
			)
		)
		(property "Voltage" "25V"
			(at 116.84 53.34 0)
			(effects
				(font
					(size 1.27 1.27)
				)
				(justify left bottom)
				(hide yes)
			)
		)
		(property "Dielectric" "X5R"
			(at 119.38 53.34 0)
			(effects
				(font
					(size 1.27 1.27)
				)
				(justify left bottom)
				(hide yes)
			)
		)
		(pin "2"
		)
		(pin "1"
		)
		(instances
			(project "OCuLink to 10GbE adapter"
				(path ""
					(reference "C101")
					(unit 1)
				)
			)
		)
	)
	(symbol
		(lib_id "antmicroCapacitors0603:C_10u_10V_X7R_0603")
		(at 53.34 73.66 90)
		(unit 1)
		(exclude_from_sim no)
		(in_bom yes)
		(on_board yes)
		(dnp no)
		(property "Reference" "C99"
			(at 55.118 69.85 90)
			(effects
				(font
					(size 1.27 1.27)
					(thickness 0.15)
				)
				(justify right)
			)
		)
		(property "Value" "C_10u_10V_X7R_0603"
			(at 63.5 58.42 0)
			(effects
				(font
					(size 1.27 1.27)
					(thickness 0.15)
				)
				(justify left bottom)
				(hide yes)
			)
		)
		(property "Footprint" "antmicro-footprints:C_0603_1608Metric"
			(at 66.04 58.42 0)
			(effects
				(font
					(size 1.27 1.27)
					(thickness 0.15)
				)
				(justify left bottom)
				(hide yes)
			)
		)
		(property "Datasheet" "https://www.murata.com/products/productdetail?partno=GRM188Z71A106KA73%23"
			(at 68.58 58.42 0)
			(effects
				(font
					(size 1.27 1.27)
					(thickness 0.15)
				)
				(justify left bottom)
				(hide yes)
			)
		)
		(property "Description" "SMD Multilayer Ceramic Capacitor,  10µF, 10V, 0603, ±10%, X7R"
			(at 53.34 73.66 0)
			(effects
				(font
					(size 1.27 1.27)
				)
				(hide yes)
			)
		)
		(property "MPN" "GRM188Z71A106KA73D"
			(at 71.12 58.42 0)
			(effects
				(font
					(size 1.27 1.27)
					(thickness 0.15)
				)
				(justify left bottom)
				(hide yes)
			)
		)
		(property "Val" "10u"
			(at 55.118 72.39 90)
			(effects
				(font
					(size 1.27 1.27)
					(thickness 0.15)
				)
				(justify right)
			)
		)
		(property "Voltage" "10V"
			(at 73.66 58.42 0)
			(effects
				(font
					(size 1.27 1.27)
					(thickness 0.15)
				)
				(justify left bottom)
				(hide yes)
			)
		)
		(property "Dielectric" "X7R"
			(at 76.2 58.42 0)
			(effects
				(font
					(size 1.27 1.27)
					(thickness 0.15)
				)
				(justify left bottom)
				(hide yes)
			)
		)
		(property "Manufacturer" "Murata"
			(at 78.74 58.42 0)
			(effects
				(font
					(size 1.27 1.27)
					(thickness 0.15)
				)
				(justify left bottom)
				(hide yes)
			)
		)
		(property "License" "Apache-2.0"
			(at 81.28 58.42 0)
			(effects
				(font
					(size 1.27 1.27)
					(thickness 0.15)
				)
				(justify left bottom)
				(hide yes)
			)
		)
		(property "Author" "Antmicro"
			(at 83.82 58.42 0)
			(effects
				(font
					(size 1.27 1.27)
					(thickness 0.15)
				)
				(justify left bottom)
				(hide yes)
			)
		)
		(pin "1"
		)
		(pin "2"
		)
		(instances
			(project "OCuLink to 10GbE adapter"
				(path ""
					(reference "C99")
					(unit 1)
				)
			)
		)
	)
	(symbol
		(lib_id "antmicropower:PWR_FLAG")
		(at 67.31 91.44 0)
		(unit 1)
		(exclude_from_sim no)
		(in_bom yes)
		(on_board yes)
		(dnp no)
		(fields_autoplaced yes)
		(property "Reference" "#FLG012"
			(at 67.31 89.535 0)
			(effects
				(font
					(size 1.27 1.27)
				)
				(hide yes)
			)
		)
		(property "Value" "PWR_FLAG"
			(at 67.31 86.36 0)
			(effects
				(font
					(size 1.27 1.27)
				)
			)
		)
		(property "Footprint" ""
			(at 67.31 91.44 0)
			(effects
				(font
					(size 1.27 1.27)
				)
				(hide yes)
			)
		)
		(property "Datasheet" ""
			(at 67.31 91.44 0)
			(effects
				(font
					(size 1.27 1.27)
				)
				(hide yes)
			)
		)
		(property "Description" ""
			(at 67.31 93.98 0)
			(effects
				(font
					(size 1.27 1.27)
				)
				(justify left bottom)
				(hide yes)
			)
		)
		(pin "1"
		)
		(instances
			(project ""
				(path ""
					(reference "#FLG012")
					(unit 1)
				)
			)
		)
	)
	(symbol
		(lib_id "antmicropower:GND")
		(at 299.72 76.2 0)
		(unit 1)
		(exclude_from_sim no)
		(in_bom yes)
		(on_board yes)
		(dnp no)
		(property "Reference" "#PWR0139"
			(at 308.61 78.74 0)
			(effects
				(font
					(size 1.27 1.27)
					(thickness 0.15)
				)
				(justify left bottom)
				(hide yes)
			)
		)
		(property "Value" "GND"
			(at 299.72 80.01 0)
			(effects
				(font
					(size 1.27 1.27)
					(thickness 0.15)
				)
			)
		)
		(property "Footprint" ""
			(at 308.61 83.82 0)
			(effects
				(font
					(size 1.27 1.27)
					(thickness 0.15)
				)
				(justify left bottom)
				(hide yes)
			)
		)
		(property "Datasheet" ""
			(at 308.61 88.9 0)
			(effects
				(font
					(size 1.27 1.27)
					(thickness 0.15)
				)
				(justify left bottom)
				(hide yes)
			)
		)
		(property "Description" ""
			(at 299.72 76.2 0)
			(effects
				(font
					(size 1.27 1.27)
				)
				(hide yes)
			)
		)
		(property "Author" "Antmicro"
			(at 308.61 83.82 0)
			(effects
				(font
					(size 1.27 1.27)
					(thickness 0.15)
				)
				(justify left bottom)
				(hide yes)
			)
		)
		(property "License" "Apache-2.0"
			(at 308.61 86.36 0)
			(effects
				(font
					(size 1.27 1.27)
					(thickness 0.15)
				)
				(justify left bottom)
				(hide yes)
			)
		)
		(pin "1"
		)
		(instances
			(project "OCuLink to 10GbE adapter"
				(path ""
					(reference "#PWR0139")
					(unit 1)
				)
			)
		)
	)
	(symbol
		(lib_id "antmicropower:GND")
		(at 361.95 133.35 0)
		(unit 1)
		(exclude_from_sim no)
		(in_bom yes)
		(on_board yes)
		(dnp no)
		(property "Reference" "#PWR0201"
			(at 370.84 135.89 0)
			(effects
				(font
					(size 1.27 1.27)
					(thickness 0.15)
				)
				(justify left bottom)
				(hide yes)
			)
		)
		(property "Value" "GND"
			(at 361.95 137.16 0)
			(effects
				(font
					(size 1.27 1.27)
					(thickness 0.15)
				)
			)
		)
		(property "Footprint" ""
			(at 370.84 140.97 0)
			(effects
				(font
					(size 1.27 1.27)
					(thickness 0.15)
				)
				(justify left bottom)
				(hide yes)
			)
		)
		(property "Datasheet" ""
			(at 370.84 146.05 0)
			(effects
				(font
					(size 1.27 1.27)
					(thickness 0.15)
				)
				(justify left bottom)
				(hide yes)
			)
		)
		(property "Description" ""
			(at 361.95 133.35 0)
			(effects
				(font
					(size 1.27 1.27)
				)
				(hide yes)
			)
		)
		(property "Author" "Antmicro"
			(at 370.84 140.97 0)
			(effects
				(font
					(size 1.27 1.27)
					(thickness 0.15)
				)
				(justify left bottom)
				(hide yes)
			)
		)
		(property "License" "Apache-2.0"
			(at 370.84 143.51 0)
			(effects
				(font
					(size 1.27 1.27)
					(thickness 0.15)
				)
				(justify left bottom)
				(hide yes)
			)
		)
		(pin "1"
		)
		(instances
			(project "OCuLink to 10GbE adapter"
				(path ""
					(reference "#PWR0201")
					(unit 1)
				)
			)
		)
	)
	(symbol
		(lib_id "antmicropower:GND")
		(at 388.62 54.61 0)
		(unit 1)
		(exclude_from_sim no)
		(in_bom yes)
		(on_board yes)
		(dnp no)
		(property "Reference" "#PWR0131"
			(at 397.51 57.15 0)
			(effects
				(font
					(size 1.27 1.27)
					(thickness 0.15)
				)
				(justify left bottom)
				(hide yes)
			)
		)
		(property "Value" "GND"
			(at 388.62 58.42 0)
			(effects
				(font
					(size 1.27 1.27)
					(thickness 0.15)
				)
			)
		)
		(property "Footprint" ""
			(at 397.51 62.23 0)
			(effects
				(font
					(size 1.27 1.27)
					(thickness 0.15)
				)
				(justify left bottom)
				(hide yes)
			)
		)
		(property "Datasheet" ""
			(at 397.51 67.31 0)
			(effects
				(font
					(size 1.27 1.27)
					(thickness 0.15)
				)
				(justify left bottom)
				(hide yes)
			)
		)
		(property "Description" ""
			(at 388.62 54.61 0)
			(effects
				(font
					(size 1.27 1.27)
				)
				(hide yes)
			)
		)
		(property "Author" "Antmicro"
			(at 397.51 62.23 0)
			(effects
				(font
					(size 1.27 1.27)
					(thickness 0.15)
				)
				(justify left bottom)
				(hide yes)
			)
		)
		(property "License" "Apache-2.0"
			(at 397.51 64.77 0)
			(effects
				(font
					(size 1.27 1.27)
					(thickness 0.15)
				)
				(justify left bottom)
				(hide yes)
			)
		)
		(pin "1"
		)
		(instances
			(project "OCuLink to 10GbE adapter"
				(path ""
					(reference "#PWR0131")
					(unit 1)
				)
			)
		)
	)
	(symbol
		(lib_id "antmicropower:PWR_FLAG")
		(at 66.04 251.46 0)
		(unit 1)
		(exclude_from_sim no)
		(in_bom yes)
		(on_board yes)
		(dnp no)
		(fields_autoplaced yes)
		(property "Reference" "#FLG019"
			(at 66.04 249.555 0)
			(effects
				(font
					(size 1.27 1.27)
				)
				(hide yes)
			)
		)
		(property "Value" "PWR_FLAG"
			(at 66.04 246.38 0)
			(effects
				(font
					(size 1.27 1.27)
				)
			)
		)
		(property "Footprint" ""
			(at 66.04 251.46 0)
			(effects
				(font
					(size 1.27 1.27)
				)
				(hide yes)
			)
		)
		(property "Datasheet" ""
			(at 66.04 251.46 0)
			(effects
				(font
					(size 1.27 1.27)
				)
				(hide yes)
			)
		)
		(property "Description" ""
			(at 66.04 254 0)
			(effects
				(font
					(size 1.27 1.27)
				)
				(justify left bottom)
				(hide yes)
			)
		)
		(pin "1"
		)
		(instances
			(project "OCuLink to 10GbE adapter"
				(path ""
					(reference "#FLG019")
					(unit 1)
				)
			)
		)
	)
	(symbol
		(lib_id "antmicroCapacitors0402:C_1u_25V_0402")
		(at 299.72 73.66 90)
		(unit 1)
		(exclude_from_sim no)
		(in_bom yes)
		(on_board yes)
		(dnp no)
		(property "Reference" "C105"
			(at 301.752 69.85 90)
			(effects
				(font
					(size 1.27 1.27)
					(thickness 0.15)
				)
				(justify right)
			)
		)
		(property "Value" "C_1u_25V_0402"
			(at 309.88 53.34 0)
			(effects
				(font
					(size 1.27 1.27)
					(thickness 0.15)
				)
				(justify left bottom)
				(hide yes)
			)
		)
		(property "Footprint" "antmicro-footprints:C_0402_1005Metric"
			(at 312.42 53.34 0)
			(effects
				(font
					(size 1.27 1.27)
					(thickness 0.15)
				)
				(justify left bottom)
				(hide yes)
			)
		)
		(property "Datasheet" "https://www.murata.com/products/productdetail?partno=GRM155R61E105KE11%23"
			(at 314.96 53.34 0)
			(effects
				(font
					(size 1.27 1.27)
					(thickness 0.15)
				)
				(justify left bottom)
				(hide yes)
			)
		)
		(property "Description" "SMD Multilayer Ceramic Capacitor, 1 µF, 25 V, 0402 [1005 Metric], ± 10%, X5R, GRM Series"
			(at 299.72 73.66 0)
			(effects
				(font
					(size 1.27 1.27)
				)
				(hide yes)
			)
		)
		(property "MPN" "GRM155R61E105KE11J"
			(at 317.5 53.34 0)
			(effects
				(font
					(size 1.27 1.27)
					(thickness 0.15)
				)
				(justify left bottom)
				(hide yes)
			)
		)
		(property "Manufacturer" "Murata"
			(at 320.04 53.34 0)
			(effects
				(font
					(size 1.27 1.27)
					(thickness 0.15)
				)
				(justify left bottom)
				(hide yes)
			)
		)
		(property "License" "Apache-2.0"
			(at 322.58 53.34 0)
			(effects
				(font
					(size 1.27 1.27)
					(thickness 0.15)
				)
				(justify left bottom)
				(hide yes)
			)
		)
		(property "Author" "Antmicro"
			(at 325.12 53.34 0)
			(effects
				(font
					(size 1.27 1.27)
					(thickness 0.15)
				)
				(justify left bottom)
				(hide yes)
			)
		)
		(property "Val" "1u"
			(at 301.752 72.39 90)
			(effects
				(font
					(size 1.27 1.27)
					(thickness 0.15)
				)
				(justify right)
			)
		)
		(property "Voltage" "25V"
			(at 327.66 53.34 0)
			(effects
				(font
					(size 1.27 1.27)
				)
				(justify left bottom)
				(hide yes)
			)
		)
		(property "Dielectric" "X5R"
			(at 330.2 53.34 0)
			(effects
				(font
					(size 1.27 1.27)
				)
				(justify left bottom)
				(hide yes)
			)
		)
		(pin "2"
		)
		(pin "1"
		)
		(instances
			(project "OCuLink to 10GbE adapter"
				(path ""
					(reference "C105")
					(unit 1)
				)
			)
		)
	)
	(symbol
		(lib_id "antmicroCapacitors0402:C_1u_25V_0402")
		(at 106.68 180.34 90)
		(unit 1)
		(exclude_from_sim no)
		(in_bom yes)
		(on_board yes)
		(dnp no)
		(property "Reference" "C177"
			(at 108.712 176.53 90)
			(effects
				(font
					(size 1.27 1.27)
					(thickness 0.15)
				)
				(justify right)
			)
		)
		(property "Value" "C_1u_25V_0402"
			(at 116.84 160.02 0)
			(effects
				(font
					(size 1.27 1.27)
					(thickness 0.15)
				)
				(justify left bottom)
				(hide yes)
			)
		)
		(property "Footprint" "antmicro-footprints:C_0402_1005Metric"
			(at 119.38 160.02 0)
			(effects
				(font
					(size 1.27 1.27)
					(thickness 0.15)
				)
				(justify left bottom)
				(hide yes)
			)
		)
		(property "Datasheet" "https://www.murata.com/products/productdetail?partno=GRM155R61E105KE11%23"
			(at 121.92 160.02 0)
			(effects
				(font
					(size 1.27 1.27)
					(thickness 0.15)
				)
				(justify left bottom)
				(hide yes)
			)
		)
		(property "Description" "SMD Multilayer Ceramic Capacitor, 1 µF, 25 V, 0402 [1005 Metric], ± 10%, X5R, GRM Series"
			(at 106.68 180.34 0)
			(effects
				(font
					(size 1.27 1.27)
				)
				(hide yes)
			)
		)
		(property "MPN" "GRM155R61E105KE11J"
			(at 124.46 160.02 0)
			(effects
				(font
					(size 1.27 1.27)
					(thickness 0.15)
				)
				(justify left bottom)
				(hide yes)
			)
		)
		(property "Manufacturer" "Murata"
			(at 127 160.02 0)
			(effects
				(font
					(size 1.27 1.27)
					(thickness 0.15)
				)
				(justify left bottom)
				(hide yes)
			)
		)
		(property "License" "Apache-2.0"
			(at 129.54 160.02 0)
			(effects
				(font
					(size 1.27 1.27)
					(thickness 0.15)
				)
				(justify left bottom)
				(hide yes)
			)
		)
		(property "Author" "Antmicro"
			(at 132.08 160.02 0)
			(effects
				(font
					(size 1.27 1.27)
					(thickness 0.15)
				)
				(justify left bottom)
				(hide yes)
			)
		)
		(property "Val" "1u"
			(at 108.712 179.07 90)
			(effects
				(font
					(size 1.27 1.27)
					(thickness 0.15)
				)
				(justify right)
			)
		)
		(property "Voltage" "25V"
			(at 134.62 160.02 0)
			(effects
				(font
					(size 1.27 1.27)
				)
				(justify left bottom)
				(hide yes)
			)
		)
		(property "Dielectric" "X5R"
			(at 137.16 160.02 0)
			(effects
				(font
					(size 1.27 1.27)
				)
				(justify left bottom)
				(hide yes)
			)
		)
		(pin "2"
		)
		(pin "1"
		)
		(instances
			(project "OCuLink to 10GbE adapter"
				(path ""
					(reference "C177")
					(unit 1)
				)
			)
		)
	)
	(symbol
		(lib_id "antmicropower:GND")
		(at 88.9 209.55 0)
		(unit 1)
		(exclude_from_sim no)
		(in_bom yes)
		(on_board yes)
		(dnp no)
		(property "Reference" "#PWR0234"
			(at 97.79 212.09 0)
			(effects
				(font
					(size 1.27 1.27)
					(thickness 0.15)
				)
				(justify left bottom)
				(hide yes)
			)
		)
		(property "Value" "GND"
			(at 88.9 213.36 0)
			(effects
				(font
					(size 1.27 1.27)
					(thickness 0.15)
				)
			)
		)
		(property "Footprint" ""
			(at 97.79 217.17 0)
			(effects
				(font
					(size 1.27 1.27)
					(thickness 0.15)
				)
				(justify left bottom)
				(hide yes)
			)
		)
		(property "Datasheet" ""
			(at 97.79 222.25 0)
			(effects
				(font
					(size 1.27 1.27)
					(thickness 0.15)
				)
				(justify left bottom)
				(hide yes)
			)
		)
		(property "Description" ""
			(at 88.9 209.55 0)
			(effects
				(font
					(size 1.27 1.27)
				)
				(hide yes)
			)
		)
		(property "Author" "Antmicro"
			(at 97.79 217.17 0)
			(effects
				(font
					(size 1.27 1.27)
					(thickness 0.15)
				)
				(justify left bottom)
				(hide yes)
			)
		)
		(property "License" "Apache-2.0"
			(at 97.79 219.71 0)
			(effects
				(font
					(size 1.27 1.27)
					(thickness 0.15)
				)
				(justify left bottom)
				(hide yes)
			)
		)
		(pin "1"
		)
		(instances
			(project "OCuLink to 10GbE adapter"
				(path ""
					(reference "#PWR0234")
					(unit 1)
				)
			)
		)
	)
	(symbol
		(lib_id "antmicropower:GND")
		(at 344.17 133.35 0)
		(unit 1)
		(exclude_from_sim no)
		(in_bom yes)
		(on_board yes)
		(dnp no)
		(property "Reference" "#PWR0199"
			(at 353.06 135.89 0)
			(effects
				(font
					(size 1.27 1.27)
					(thickness 0.15)
				)
				(justify left bottom)
				(hide yes)
			)
		)
		(property "Value" "GND"
			(at 344.17 137.16 0)
			(effects
				(font
					(size 1.27 1.27)
					(thickness 0.15)
				)
			)
		)
		(property "Footprint" ""
			(at 353.06 140.97 0)
			(effects
				(font
					(size 1.27 1.27)
					(thickness 0.15)
				)
				(justify left bottom)
				(hide yes)
			)
		)
		(property "Datasheet" ""
			(at 353.06 146.05 0)
			(effects
				(font
					(size 1.27 1.27)
					(thickness 0.15)
				)
				(justify left bottom)
				(hide yes)
			)
		)
		(property "Description" ""
			(at 344.17 133.35 0)
			(effects
				(font
					(size 1.27 1.27)
				)
				(hide yes)
			)
		)
		(property "Author" "Antmicro"
			(at 353.06 140.97 0)
			(effects
				(font
					(size 1.27 1.27)
					(thickness 0.15)
				)
				(justify left bottom)
				(hide yes)
			)
		)
		(property "License" "Apache-2.0"
			(at 353.06 143.51 0)
			(effects
				(font
					(size 1.27 1.27)
					(thickness 0.15)
				)
				(justify left bottom)
				(hide yes)
			)
		)
		(pin "1"
		)
		(instances
			(project "OCuLink to 10GbE adapter"
				(path ""
					(reference "#PWR0199")
					(unit 1)
				)
			)
		)
	)
	(symbol
		(lib_id "antmicropower:GND")
		(at 106.68 129.54 0)
		(unit 1)
		(exclude_from_sim no)
		(in_bom yes)
		(on_board yes)
		(dnp no)
		(property "Reference" "#PWR0193"
			(at 115.57 132.08 0)
			(effects
				(font
					(size 1.27 1.27)
					(thickness 0.15)
				)
				(justify left bottom)
				(hide yes)
			)
		)
		(property "Value" "GND"
			(at 106.68 133.35 0)
			(effects
				(font
					(size 1.27 1.27)
					(thickness 0.15)
				)
			)
		)
		(property "Footprint" ""
			(at 115.57 137.16 0)
			(effects
				(font
					(size 1.27 1.27)
					(thickness 0.15)
				)
				(justify left bottom)
				(hide yes)
			)
		)
		(property "Datasheet" ""
			(at 115.57 142.24 0)
			(effects
				(font
					(size 1.27 1.27)
					(thickness 0.15)
				)
				(justify left bottom)
				(hide yes)
			)
		)
		(property "Description" ""
			(at 106.68 129.54 0)
			(effects
				(font
					(size 1.27 1.27)
				)
				(hide yes)
			)
		)
		(property "Author" "Antmicro"
			(at 115.57 137.16 0)
			(effects
				(font
					(size 1.27 1.27)
					(thickness 0.15)
				)
				(justify left bottom)
				(hide yes)
			)
		)
		(property "License" "Apache-2.0"
			(at 115.57 139.7 0)
			(effects
				(font
					(size 1.27 1.27)
					(thickness 0.15)
				)
				(justify left bottom)
				(hide yes)
			)
		)
		(pin "1"
		)
		(instances
			(project "OCuLink to 10GbE adapter"
				(path ""
					(reference "#PWR0193")
					(unit 1)
				)
			)
		)
	)
	(symbol
		(lib_id "antmicropower:GND")
		(at 388.62 133.35 0)
		(unit 1)
		(exclude_from_sim no)
		(in_bom yes)
		(on_board yes)
		(dnp no)
		(property "Reference" "#PWR0204"
			(at 397.51 135.89 0)
			(effects
				(font
					(size 1.27 1.27)
					(thickness 0.15)
				)
				(justify left bottom)
				(hide yes)
			)
		)
		(property "Value" "GND"
			(at 388.62 137.16 0)
			(effects
				(font
					(size 1.27 1.27)
					(thickness 0.15)
				)
			)
		)
		(property "Footprint" ""
			(at 397.51 140.97 0)
			(effects
				(font
					(size 1.27 1.27)
					(thickness 0.15)
				)
				(justify left bottom)
				(hide yes)
			)
		)
		(property "Datasheet" ""
			(at 397.51 146.05 0)
			(effects
				(font
					(size 1.27 1.27)
					(thickness 0.15)
				)
				(justify left bottom)
				(hide yes)
			)
		)
		(property "Description" ""
			(at 388.62 133.35 0)
			(effects
				(font
					(size 1.27 1.27)
				)
				(hide yes)
			)
		)
		(property "Author" "Antmicro"
			(at 397.51 140.97 0)
			(effects
				(font
					(size 1.27 1.27)
					(thickness 0.15)
				)
				(justify left bottom)
				(hide yes)
			)
		)
		(property "License" "Apache-2.0"
			(at 397.51 143.51 0)
			(effects
				(font
					(size 1.27 1.27)
					(thickness 0.15)
				)
				(justify left bottom)
				(hide yes)
			)
		)
		(pin "1"
		)
		(instances
			(project "OCuLink to 10GbE adapter"
				(path ""
					(reference "#PWR0204")
					(unit 1)
				)
			)
		)
	)
	(symbol
		(lib_id "antmicroCapacitors0402:C_1u_25V_0402")
		(at 361.95 73.66 90)
		(unit 1)
		(exclude_from_sim no)
		(in_bom yes)
		(on_board yes)
		(dnp no)
		(property "Reference" "C112"
			(at 363.982 69.85 90)
			(effects
				(font
					(size 1.27 1.27)
					(thickness 0.15)
				)
				(justify right)
			)
		)
		(property "Value" "C_1u_25V_0402"
			(at 372.11 53.34 0)
			(effects
				(font
					(size 1.27 1.27)
					(thickness 0.15)
				)
				(justify left bottom)
				(hide yes)
			)
		)
		(property "Footprint" "antmicro-footprints:C_0402_1005Metric"
			(at 374.65 53.34 0)
			(effects
				(font
					(size 1.27 1.27)
					(thickness 0.15)
				)
				(justify left bottom)
				(hide yes)
			)
		)
		(property "Datasheet" "https://www.murata.com/products/productdetail?partno=GRM155R61E105KE11%23"
			(at 377.19 53.34 0)
			(effects
				(font
					(size 1.27 1.27)
					(thickness 0.15)
				)
				(justify left bottom)
				(hide yes)
			)
		)
		(property "Description" "SMD Multilayer Ceramic Capacitor, 1 µF, 25 V, 0402 [1005 Metric], ± 10%, X5R, GRM Series"
			(at 361.95 73.66 0)
			(effects
				(font
					(size 1.27 1.27)
				)
				(hide yes)
			)
		)
		(property "MPN" "GRM155R61E105KE11J"
			(at 379.73 53.34 0)
			(effects
				(font
					(size 1.27 1.27)
					(thickness 0.15)
				)
				(justify left bottom)
				(hide yes)
			)
		)
		(property "Manufacturer" "Murata"
			(at 382.27 53.34 0)
			(effects
				(font
					(size 1.27 1.27)
					(thickness 0.15)
				)
				(justify left bottom)
				(hide yes)
			)
		)
		(property "License" "Apache-2.0"
			(at 384.81 53.34 0)
			(effects
				(font
					(size 1.27 1.27)
					(thickness 0.15)
				)
				(justify left bottom)
				(hide yes)
			)
		)
		(property "Author" "Antmicro"
			(at 387.35 53.34 0)
			(effects
				(font
					(size 1.27 1.27)
					(thickness 0.15)
				)
				(justify left bottom)
				(hide yes)
			)
		)
		(property "Val" "1u"
			(at 363.982 72.39 90)
			(effects
				(font
					(size 1.27 1.27)
					(thickness 0.15)
				)
				(justify right)
			)
		)
		(property "Voltage" "25V"
			(at 389.89 53.34 0)
			(effects
				(font
					(size 1.27 1.27)
				)
				(justify left bottom)
				(hide yes)
			)
		)
		(property "Dielectric" "X5R"
			(at 392.43 53.34 0)
			(effects
				(font
					(size 1.27 1.27)
				)
				(justify left bottom)
				(hide yes)
			)
		)
		(pin "2"
		)
		(pin "1"
		)
		(instances
			(project "OCuLink to 10GbE adapter"
				(path ""
					(reference "C112")
					(unit 1)
				)
			)
		)
	)
	(symbol
		(lib_id "antmicropower:GND")
		(at 41.91 129.54 0)
		(unit 1)
		(exclude_from_sim no)
		(in_bom yes)
		(on_board yes)
		(dnp no)
		(property "Reference" "#PWR0187"
			(at 50.8 132.08 0)
			(effects
				(font
					(size 1.27 1.27)
					(thickness 0.15)
				)
				(justify left bottom)
				(hide yes)
			)
		)
		(property "Value" "GND"
			(at 41.91 133.35 0)
			(effects
				(font
					(size 1.27 1.27)
					(thickness 0.15)
				)
			)
		)
		(property "Footprint" ""
			(at 50.8 137.16 0)
			(effects
				(font
					(size 1.27 1.27)
					(thickness 0.15)
				)
				(justify left bottom)
				(hide yes)
			)
		)
		(property "Datasheet" ""
			(at 50.8 142.24 0)
			(effects
				(font
					(size 1.27 1.27)
					(thickness 0.15)
				)
				(justify left bottom)
				(hide yes)
			)
		)
		(property "Description" ""
			(at 41.91 129.54 0)
			(effects
				(font
					(size 1.27 1.27)
				)
				(hide yes)
			)
		)
		(property "Author" "Antmicro"
			(at 50.8 137.16 0)
			(effects
				(font
					(size 1.27 1.27)
					(thickness 0.15)
				)
				(justify left bottom)
				(hide yes)
			)
		)
		(property "License" "Apache-2.0"
			(at 50.8 139.7 0)
			(effects
				(font
					(size 1.27 1.27)
					(thickness 0.15)
				)
				(justify left bottom)
				(hide yes)
			)
		)
		(pin "1"
		)
		(instances
			(project "OCuLink to 10GbE adapter"
				(path ""
					(reference "#PWR0187")
					(unit 1)
				)
			)
		)
	)
	(symbol
		(lib_id "antmicroCapacitors0603:C_10u_10V_X7R_0603")
		(at 308.61 130.81 90)
		(unit 1)
		(exclude_from_sim no)
		(in_bom yes)
		(on_board yes)
		(dnp no)
		(property "Reference" "C147"
			(at 310.642 127 90)
			(effects
				(font
					(size 1.27 1.27)
					(thickness 0.15)
				)
				(justify right)
			)
		)
		(property "Value" "C_10u_10V_X7R_0603"
			(at 318.77 115.57 0)
			(effects
				(font
					(size 1.27 1.27)
					(thickness 0.15)
				)
				(justify left bottom)
				(hide yes)
			)
		)
		(property "Footprint" "antmicro-footprints:C_0603_1608Metric"
			(at 321.31 115.57 0)
			(effects
				(font
					(size 1.27 1.27)
					(thickness 0.15)
				)
				(justify left bottom)
				(hide yes)
			)
		)
		(property "Datasheet" "https://www.murata.com/products/productdetail?partno=GRM188Z71A106KA73%23"
			(at 323.85 115.57 0)
			(effects
				(font
					(size 1.27 1.27)
					(thickness 0.15)
				)
				(justify left bottom)
				(hide yes)
			)
		)
		(property "Description" "SMD Multilayer Ceramic Capacitor,  10µF, 10V, 0603, ±10%, X7R"
			(at 308.61 130.81 0)
			(effects
				(font
					(size 1.27 1.27)
				)
				(hide yes)
			)
		)
		(property "MPN" "GRM188Z71A106KA73D"
			(at 326.39 115.57 0)
			(effects
				(font
					(size 1.27 1.27)
					(thickness 0.15)
				)
				(justify left bottom)
				(hide yes)
			)
		)
		(property "Val" "10u"
			(at 310.642 129.54 90)
			(effects
				(font
					(size 1.27 1.27)
					(thickness 0.15)
				)
				(justify right)
			)
		)
		(property "Voltage" "10V"
			(at 328.93 115.57 0)
			(effects
				(font
					(size 1.27 1.27)
					(thickness 0.15)
				)
				(justify left bottom)
				(hide yes)
			)
		)
		(property "Dielectric" "X7R"
			(at 331.47 115.57 0)
			(effects
				(font
					(size 1.27 1.27)
					(thickness 0.15)
				)
				(justify left bottom)
				(hide yes)
			)
		)
		(property "Manufacturer" "Murata"
			(at 334.01 115.57 0)
			(effects
				(font
					(size 1.27 1.27)
					(thickness 0.15)
				)
				(justify left bottom)
				(hide yes)
			)
		)
		(property "License" "Apache-2.0"
			(at 336.55 115.57 0)
			(effects
				(font
					(size 1.27 1.27)
					(thickness 0.15)
				)
				(justify left bottom)
				(hide yes)
			)
		)
		(property "Author" "Antmicro"
			(at 339.09 115.57 0)
			(effects
				(font
					(size 1.27 1.27)
					(thickness 0.15)
				)
				(justify left bottom)
				(hide yes)
			)
		)
		(pin "1"
		)
		(pin "2"
		)
		(instances
			(project "OCuLink to 10GbE adapter"
				(path ""
					(reference "C147")
					(unit 1)
				)
			)
		)
	)
	(symbol
		(lib_id "antmicropower:GND")
		(at 299.72 133.35 0)
		(unit 1)
		(exclude_from_sim no)
		(in_bom yes)
		(on_board yes)
		(dnp no)
		(property "Reference" "#PWR0195"
			(at 308.61 135.89 0)
			(effects
				(font
					(size 1.27 1.27)
					(thickness 0.15)
				)
				(justify left bottom)
				(hide yes)
			)
		)
		(property "Value" "GND"
			(at 299.72 137.16 0)
			(effects
				(font
					(size 1.27 1.27)
					(thickness 0.15)
				)
			)
		)
		(property "Footprint" ""
			(at 308.61 140.97 0)
			(effects
				(font
					(size 1.27 1.27)
					(thickness 0.15)
				)
				(justify left bottom)
				(hide yes)
			)
		)
		(property "Datasheet" ""
			(at 308.61 146.05 0)
			(effects
				(font
					(size 1.27 1.27)
					(thickness 0.15)
				)
				(justify left bottom)
				(hide yes)
			)
		)
		(property "Description" ""
			(at 299.72 133.35 0)
			(effects
				(font
					(size 1.27 1.27)
				)
				(hide yes)
			)
		)
		(property "Author" "Antmicro"
			(at 308.61 140.97 0)
			(effects
				(font
					(size 1.27 1.27)
					(thickness 0.15)
				)
				(justify left bottom)
				(hide yes)
			)
		)
		(property "License" "Apache-2.0"
			(at 308.61 143.51 0)
			(effects
				(font
					(size 1.27 1.27)
					(thickness 0.15)
				)
				(justify left bottom)
				(hide yes)
			)
		)
		(pin "1"
		)
		(instances
			(project "OCuLink to 10GbE adapter"
				(path ""
					(reference "#PWR0195")
					(unit 1)
				)
			)
		)
	)
	(symbol
		(lib_id "antmicropower:GND")
		(at 308.61 133.35 0)
		(unit 1)
		(exclude_from_sim no)
		(in_bom yes)
		(on_board yes)
		(dnp no)
		(property "Reference" "#PWR0196"
			(at 317.5 135.89 0)
			(effects
				(font
					(size 1.27 1.27)
					(thickness 0.15)
				)
				(justify left bottom)
				(hide yes)
			)
		)
		(property "Value" "GND"
			(at 308.61 137.16 0)
			(effects
				(font
					(size 1.27 1.27)
					(thickness 0.15)
				)
			)
		)
		(property "Footprint" ""
			(at 317.5 140.97 0)
			(effects
				(font
					(size 1.27 1.27)
					(thickness 0.15)
				)
				(justify left bottom)
				(hide yes)
			)
		)
		(property "Datasheet" ""
			(at 317.5 146.05 0)
			(effects
				(font
					(size 1.27 1.27)
					(thickness 0.15)
				)
				(justify left bottom)
				(hide yes)
			)
		)
		(property "Description" ""
			(at 308.61 133.35 0)
			(effects
				(font
					(size 1.27 1.27)
				)
				(hide yes)
			)
		)
		(property "Author" "Antmicro"
			(at 317.5 140.97 0)
			(effects
				(font
					(size 1.27 1.27)
					(thickness 0.15)
				)
				(justify left bottom)
				(hide yes)
			)
		)
		(property "License" "Apache-2.0"
			(at 317.5 143.51 0)
			(effects
				(font
					(size 1.27 1.27)
					(thickness 0.15)
				)
				(justify left bottom)
				(hide yes)
			)
		)
		(pin "1"
		)
		(instances
			(project "OCuLink to 10GbE adapter"
				(path ""
					(reference "#PWR0196")
					(unit 1)
				)
			)
		)
	)
	(symbol
		(lib_id "antmicropower:VCC")
		(at 234.95 179.07 90)
		(unit 1)
		(exclude_from_sim no)
		(in_bom yes)
		(on_board yes)
		(dnp no)
		(fields_autoplaced yes)
		(property "Reference" "#PWR0310"
			(at 238.76 179.07 0)
			(effects
				(font
					(size 1.27 1.27)
				)
				(hide yes)
			)
		)
		(property "Value" "VCCA"
			(at 231.14 179.0699 90)
			(effects
				(font
					(size 1.27 1.27)
				)
				(justify left)
			)
		)
		(property "Footprint" ""
			(at 234.95 179.07 0)
			(effects
				(font
					(size 1.27 1.27)
				)
				(hide yes)
			)
		)
		(property "Datasheet" ""
			(at 234.95 179.07 0)
			(effects
				(font
					(size 1.27 1.27)
				)
				(hide yes)
			)
		)
		(property "Description" ""
			(at 234.95 179.07 0)
			(effects
				(font
					(size 1.27 1.27)
				)
				(hide yes)
			)
		)
		(pin "1"
		)
		(instances
			(project "oculink-to-10gbe-adapter"
				(path ""
					(reference "#PWR0310")
					(unit 1)
				)
			)
		)
	)
	(symbol
		(lib_id "antmicroInterfaceControllers:EZX710AT2_S_LMR5")
		(at 217.17 90.17 0)
		(unit 8)
		(exclude_from_sim no)
		(in_bom yes)
		(on_board yes)
		(dnp no)
		(fields_autoplaced yes)
		(property "Reference" "U9"
			(at 242.57 82.55 0)
			(effects
				(font
					(size 1.27 1.27)
					(thickness 0.15)
				)
			)
		)
		(property "Value" "EZX710AT2_S_LMR5"
			(at 293.37 95.25 0)
			(effects
				(font
					(size 1.27 1.27)
					(thickness 0.15)
				)
				(justify left bottom)
				(hide yes)
			)
		)
		(property "Footprint" "antmicro-footprints:FCBGA-503_22x22mm_Layout21x24_P1mm"
			(at 293.37 97.79 0)
			(effects
				(font
					(size 1.27 1.27)
					(thickness 0.15)
				)
				(justify left bottom)
				(hide yes)
			)
		)
		(property "Datasheet" "https://www.google.com/url?sa=t&source=web&rct=j&opi=89978449&url=https://cdrdv2-public.intel.com/596333/596333_X710-TM4_Datasheet_v_2_4.pdf&ved=2ahUKEwiSuv20_sCOAxXVCRAIHdxGO_UQFnoECBEQAQ&usg=AOvVaw1CjGyrGWE8ZvOdw4VBsY6U"
			(at 293.37 100.33 0)
			(effects
				(font
					(size 1.27 1.27)
					(thickness 0.15)
				)
				(justify left bottom)
				(hide yes)
			)
		)
		(property "Description" "Ethernet ICs Intel Ethernet Controller 10 Gigabit X7"
			(at 293.37 102.87 0)
			(effects
				(font
					(size 1.27 1.27)
					(thickness 0.15)
				)
				(justify left bottom)
				(hide yes)
			)
		)
		(property "MPN" "EZX710AT2 S LMR5"
			(at 242.57 85.09 0)
			(effects
				(font
					(size 1.27 1.27)
					(thickness 0.15)
				)
			)
		)
		(property "Manufacturer" "Intel"
			(at 293.37 105.41 0)
			(effects
				(font
					(size 1.27 1.27)
					(thickness 0.15)
				)
				(justify left bottom)
				(hide yes)
			)
		)
		(property "Author" "Antmicro"
			(at 293.37 107.95 0)
			(effects
				(font
					(size 1.27 1.27)
					(thickness 0.15)
				)
				(justify left bottom)
				(hide yes)
			)
		)
		(property "License" "Apache-2.0"
			(at 293.37 110.49 0)
			(effects
				(font
					(size 1.27 1.27)
					(thickness 0.15)
				)
				(justify left bottom)
				(hide yes)
			)
		)
		(pin "N3"
		)
		(pin "V38"
		)
		(pin "T38"
		)
		(pin "B38"
		)
		(pin "L31"
		)
		(pin "D6"
		)
		(pin "R27"
		)
		(pin "W41"
		)
		(pin "V42"
		)
		(pin "F14"
		)
		(pin "D22"
		)
		(pin "D8"
		)
		(pin "AD26"
		)
		(pin "L25"
		)
		(pin "B40"
		)
		(pin "B34"
		)
		(pin "G11"
		)
		(pin "H16"
		)
		(pin "P36"
		)
		(pin "L11"
		)
		(pin "L13"
		)
		(pin "G29"
		)
		(pin "G31"
		)
		(pin "C13"
		)
		(pin "C15"
		)
		(pin "J31"
		)
		(pin "J35"
		)
		(pin "V36"
		)
		(pin "P22"
		)
		(pin "AC27"
		)
		(pin "AC29"
		)
		(pin "R29"
		)
		(pin "T32"
		)
		(pin "T36"
		)
		(pin "AD32"
		)
		(pin "G3"
		)
		(pin "K4"
		)
		(pin "Y12"
		)
		(pin "U7"
		)
		(pin "AB10"
		)
		(pin "AD20"
		)
		(pin "M8"
		)
		(pin "A5"
		)
		(pin "A33"
		)
		(pin "AC31"
		)
		(pin "AA27"
		)
		(pin "G5"
		)
		(pin "U33"
		)
		(pin "U31"
		)
		(pin "A17"
		)
		(pin "AD22"
		)
		(pin "A27"
		)
		(pin "V28"
		)
		(pin "AC23"
		)
		(pin "AC25"
		)
		(pin "H12"
		)
		(pin "Y30"
		)
		(pin "W15"
		)
		(pin "W17"
		)
		(pin "J27"
		)
		(pin "J29"
		)
		(pin "P30"
		)
		(pin "R31"
		)
		(pin "K6"
		)
		(pin "E35"
		)
		(pin "E37"
		)
		(pin "U27"
		)
		(pin "F2"
		)
		(pin "J41"
		)
		(pin "A13"
		)
		(pin "H14"
		)
		(pin "J1"
		)
		(pin "G17"
		)
		(pin "K22"
		)
		(pin "R41"
		)
		(pin "F36"
		)
		(pin "K18"
		)
		(pin "K20"
		)
		(pin "R39"
		)
		(pin "M14"
		)
		(pin "M16"
		)
		(pin "D2"
		)
		(pin "R23"
		)
		(pin "V40"
		)
		(pin "L41"
		)
		(pin "F6"
		)
		(pin "M24"
		)
		(pin "P28"
		)
		(pin "J23"
		)
		(pin "J17"
		)
		(pin "U3"
		)
		(pin "L35"
		)
		(pin "G15"
		)
		(pin "AD38"
		)
		(pin "AD42"
		)
		(pin "AB28"
		)
		(pin "AB12"
		)
		(pin "AB24"
		)
		(pin "N29"
		)
		(pin "P32"
		)
		(pin "M40"
		)
		(pin "B28"
		)
		(pin "K40"
		)
		(pin "B36"
		)
		(pin "V8"
		)
		(pin "V10"
		)
		(pin "P26"
		)
		(pin "E39"
		)
		(pin "AB34"
		)
		(pin "AB36"
		)
		(pin "H10"
		)
		(pin "Y16"
		)
		(pin "B30"
		)
		(pin "B6"
		)
		(pin "J37"
		)
		(pin "N9"
		)
		(pin "M2"
		)
		(pin "W7"
		)
		(pin "E15"
		)
		(pin "AB18"
		)
		(pin "C33"
		)
		(pin "C35"
		)
		(pin "Y22"
		)
		(pin "AB42"
		)
		(pin "W3"
		)
		(pin "U1"
		)
		(pin "Y2"
		)
		(pin "F12"
		)
		(pin "P6"
		)
		(pin "E3"
		)
		(pin "L23"
		)
		(pin "M22"
		)
		(pin "V34"
		)
		(pin "G27"
		)
		(pin "H18"
		)
		(pin "A39"
		)
		(pin "B26"
		)
		(pin "E11"
		)
		(pin "J19"
		)
		(pin "L19"
		)
		(pin "L21"
		)
		(pin "H36"
		)
		(pin "H38"
		)
		(pin "H32"
		)
		(pin "H34"
		)
		(pin "K42"
		)
		(pin "G21"
		)
		(pin "AB16"
		)
		(pin "J21"
		)
		(pin "AA17"
		)
		(pin "AA19"
		)
		(pin "M28"
		)
		(pin "P12"
		)
		(pin "P14"
		)
		(pin "P16"
		)
		(pin "P18"
		)
		(pin "P20"
		)
		(pin "R35"
		)
		(pin "D20"
		)
		(pin "C21"
		)
		(pin "T34"
		)
		(pin "U21"
		)
		(pin "M42"
		)
		(pin "V22"
		)
		(pin "AC7"
		)
		(pin "AC9"
		)
		(pin "F30"
		)
		(pin "F32"
		)
		(pin "F34"
		)
		(pin "E9"
		)
		(pin "D12"
		)
		(pin "AD40"
		)
		(pin "E41"
		)
		(pin "A29"
		)
		(pin "A25"
		)
		(pin "F22"
		)
		(pin "D4"
		)
		(pin "W23"
		)
		(pin "U11"
		)
		(pin "U13"
		)
		(pin "R19"
		)
		(pin "R21"
		)
		(pin "AA5"
		)
		(pin "AC5"
		)
		(pin "AD4"
		)
		(pin "AB2"
		)
		(pin "AA1"
		)
		(pin "T28"
		)
		(pin "AB30"
		)
		(pin "AB32"
		)
		(pin "N15"
		)
		(pin "W13"
		)
		(pin "N37"
		)
		(pin "U41"
		)
		(pin "H8"
		)
		(pin "G19"
		)
		(pin "E13"
		)
		(pin "N39"
		)
		(pin "N7"
		)
		(pin "M4"
		)
		(pin "AA31"
		)
		(pin "AD8"
		)
		(pin "B14"
		)
		(pin "E5"
		)
		(pin "V16"
		)
		(pin "V18"
		)
		(pin "M36"
		)
		(pin "U23"
		)
		(pin "Y28"
		)
		(pin "Y32"
		)
		(pin "Y36"
		)
		(pin "F24"
		)
		(pin "F26"
		)
		(pin "F28"
		)
		(pin "L3"
		)
		(pin "H2"
		)
		(pin "M18"
		)
		(pin "M20"
		)
		(pin "P10"
		)
		(pin "U29"
		)
		(pin "N11"
		)
		(pin "N13"
		)
		(pin "Y24"
		)
		(pin "D10"
		)
		(pin "C9"
		)
		(pin "H26"
		)
		(pin "C3"
		)
		(pin "R5"
		)
		(pin "AC15"
		)
		(pin "AC17"
		)
		(pin "K32"
		)
		(pin "V12"
		)
		(pin "V14"
		)
		(pin "K14"
		)
		(pin "K16"
		)
		(pin "F38"
		)
		(pin "D32"
		)
		(pin "AC11"
		)
		(pin "AC13"
		)
		(pin "U15"
		)
		(pin "U17"
		)
		(pin "D18"
		)
		(pin "Y8"
		)
		(pin "A21"
		)
		(pin "A31"
		)
		(pin "AC39"
		)
		(pin "U5"
		)
		(pin "B16"
		)
		(pin "B2"
		)
		(pin "T16"
		)
		(pin "T18"
		)
		(pin "T20"
		)
		(pin "U19"
		)
		(pin "W9"
		)
		(pin "L27"
		)
		(pin "AA21"
		)
		(pin "AA23"
		)
		(pin "E21"
		)
		(pin "E19"
		)
		(pin "M10"
		)
		(pin "M12"
		)
		(pin "P2"
		)
		(pin "R1"
		)
		(pin "T40"
		)
		(pin "U25"
		)
		(pin "R9"
		)
		(pin "N27"
		)
		(pin "W31"
		)
		(pin "W33"
		)
		(pin "V6"
		)
		(pin "N1"
		)
		(pin "J13"
		)
		(pin "P8"
		)
		(pin "B10"
		)
		(pin "N5"
		)
		(pin "B8"
		)
		(pin "C11"
		)
		(pin "Y4"
		)
		(pin "Y40"
		)
		(pin "Y6"
		)
		(pin "M34"
		)
		(pin "A19"
		)
		(pin "A3"
		)
		(pin "T4"
		)
		(pin "C37"
		)
		(pin "C39"
		)
		(pin "T6"
		)
		(pin "F4"
		)
		(pin "P4"
		)
		(pin "L29"
		)
		(pin "M32"
		)
		(pin "W35"
		)
		(pin "W37"
		)
		(pin "R7"
		)
		(pin "K30"
		)
		(pin "M6"
		)
		(pin "P38"
		)
		(pin "G33"
		)
		(pin "G35"
		)
		(pin "J11"
		)
		(pin "T24"
		)
		(pin "B18"
		)
		(pin "B24"
		)
		(pin "U37"
		)
		(pin "Y42"
		)
		(pin "AD12"
		)
		(pin "AD18"
		)
		(pin "G9"
		)
		(pin "R33"
		)
		(pin "E27"
		)
		(pin "E29"
		)
		(pin "AD36"
		)
		(pin "M30"
		)
		(pin "N31"
		)
		(pin "AC19"
		)
		(pin "AC21"
		)
		(pin "V32"
		)
		(pin "V30"
		)
		(pin "N21"
		)
		(pin "R13"
		)
		(pin "Y10"
		)
		(pin "T26"
		)
		(pin "D28"
		)
		(pin "D36"
		)
		(pin "D38"
		)
		(pin "AC37"
		)
		(pin "AC41"
		)
		(pin "K10"
		)
		(pin "K12"
		)
		(pin "K38"
		)
		(pin "K8"
		)
		(pin "AB40"
		)
		(pin "AB6"
		)
		(pin "F20"
		)
		(pin "AA13"
		)
		(pin "AA15"
		)
		(pin "T22"
		)
		(pin "K24"
		)
		(pin "R3"
		)
		(pin "N33"
		)
		(pin "F10"
		)
		(pin "Y34"
		)
		(pin "V26"
		)
		(pin "W5"
		)
		(pin "G7"
		)
		(pin "G13"
		)
		(pin "A11"
		)
		(pin "A15"
		)
		(pin "T30"
		)
		(pin "U35"
		)
		(pin "AD28"
		)
		(pin "C17"
		)
		(pin "C19"
		)
		(pin "N35"
		)
		(pin "H40"
		)
		(pin "AA7"
		)
		(pin "H4"
		)
		(pin "H6"
		)
		(pin "AC35"
		)
		(pin "J33"
		)
		(pin "G39"
		)
		(pin "T8"
		)
		(pin "R11"
		)
		(pin "AA39"
		)
		(pin "F40"
		)
		(pin "F42"
		)
		(pin "G41"
		)
		(pin "P34"
		)
		(pin "N25"
		)
		(pin "U9"
		)
		(pin "A37"
		)
		(pin "C23"
		)
		(pin "C25"
		)
		(pin "L33"
		)
		(pin "AB20"
		)
		(pin "AB26"
		)
		(pin "AD30"
		)
		(pin "AD34"
		)
		(pin "J25"
		)
		(pin "AA37"
		)
		(pin "AA41"
		)
		(pin "AD14"
		)
		(pin "M26"
		)
		(pin "T10"
		)
		(pin "T12"
		)
		(pin "T14"
		)
		(pin "E17"
		)
		(pin "B20"
		)
		(pin "B4"
		)
		(pin "G23"
		)
		(pin "H24"
		)
		(pin "A9"
		)
		(pin "N17"
		)
		(pin "N19"
		)
		(pin "R25"
		)
		(pin "AC3"
		)
		(pin "AC33"
		)
		(pin "P24"
		)
		(pin "L7"
		)
		(pin "F18"
		)
		(pin "V20"
		)
		(pin "W29"
		)
		(pin "A35"
		)
		(pin "U39"
		)
		(pin "W39"
		)
		(pin "Y14"
		)
		(pin "Y26"
		)
		(pin "N41"
		)
		(pin "P40"
		)
		(pin "K2"
		)
		(pin "P42"
		)
		(pin "AB22"
		)
		(pin "W19"
		)
		(pin "W21"
		)
		(pin "J15"
		)
		(pin "F16"
		)
		(pin "L39"
		)
		(pin "M38"
		)
		(pin "V24"
		)
		(pin "L37"
		)
		(pin "D14"
		)
		(pin "C5"
		)
		(pin "C7"
		)
		(pin "AA9"
		)
		(pin "AB14"
		)
		(pin "H42"
		)
		(pin "W25"
		)
		(pin "L5"
		)
		(pin "C41"
		)
		(pin "D24"
		)
		(pin "D26"
		)
		(pin "AA25"
		)
		(pin "AA29"
		)
		(pin "E7"
		)
		(pin "V4"
		)
		(pin "AA35"
		)
		(pin "T42"
		)
		(pin "Y18"
		)
		(pin "A23"
		)
		(pin "R15"
		)
		(pin "R17"
		)
		(pin "H22"
		)
		(pin "J3"
		)
		(pin "E1"
		)
		(pin "N23"
		)
		(pin "G1"
		)
		(pin "F8"
		)
		(pin "Y20"
		)
		(pin "H28"
		)
		(pin "H30"
		)
		(pin "C27"
		)
		(pin "C29"
		)
		(pin "J9"
		)
		(pin "J7"
		)
		(pin "AD10"
		)
		(pin "AD6"
		)
		(pin "B12"
		)
		(pin "W27"
		)
		(pin "H20"
		)
		(pin "W11"
		)
		(pin "L9"
		)
		(pin "D40"
		)
		(pin "E31"
		)
		(pin "E33"
		)
		(pin "AD2"
		)
		(pin "AD24"
		)
		(pin "AB38"
		)
		(pin "AB4"
		)
		(pin "D34"
		)
		(pin "D30"
		)
		(pin "L1"
		)
		(pin "D16"
		)
		(pin "G25"
		)
		(pin "G37"
		)
		(pin "L15"
		)
		(pin "L17"
		)
		(pin "K34"
		)
		(pin "K36"
		)
		(pin "C1"
		)
		(pin "B42"
		)
		(pin "A41"
		)
		(pin "K26"
		)
		(pin "K28"
		)
		(pin "AA3"
		)
		(pin "AA33"
		)
		(pin "A7"
		)
		(pin "AA11"
		)
		(pin "AB8"
		)
		(pin "AC1"
		)
		(pin "E23"
		)
		(pin "E25"
		)
		(pin "Y38"
		)
		(pin "B22"
		)
		(pin "B32"
		)
		(pin "C31"
		)
		(pin "J5"
		)
		(pin "T2"
		)
		(pin "V2"
		)
		(pin "R37"
		)
		(pin "J39"
		)
		(pin "D42"
		)
		(pin "AD16"
		)
		(pin "W1"
		)
		(instances
			(project "OCuLink to 10GbE adapter"
				(path ""
					(reference "U9")
					(unit 8)
				)
			)
		)
	)
	(symbol
		(lib_id "antmicroCapacitors0402:C_100n_0402")
		(at 39.37 233.68 90)
		(unit 1)
		(exclude_from_sim no)
		(in_bom yes)
		(on_board yes)
		(dnp no)
		(property "Reference" "C185"
			(at 41.402 229.87 90)
			(effects
				(font
					(size 1.27 1.27)
					(thickness 0.15)
				)
				(justify right)
			)
		)
		(property "Value" "C_100n_0402"
			(at 62.23 218.44 0)
			(effects
				(font
					(size 1.27 1.27)
					(thickness 0.15)
				)
				(justify left bottom)
				(hide yes)
			)
		)
		(property "Footprint" "antmicro-footprints:C_0402_1005Metric"
			(at 64.77 218.44 0)
			(effects
				(font
					(size 1.27 1.27)
					(thickness 0.15)
				)
				(justify left bottom)
				(hide yes)
			)
		)
		(property "Datasheet" "https://www.murata.com/products/productdetail?partno=GRM155R61H104KE14%23"
			(at 67.31 218.44 0)
			(effects
				(font
					(size 1.27 1.27)
					(thickness 0.15)
				)
				(justify left bottom)
				(hide yes)
			)
		)
		(property "Description" "SMD Multilayer Ceramic Capacitor, 0.1 µF, 50 V, 0402 [1005 Metric], ± 10%, X5R, GRM Series"
			(at 39.37 233.68 0)
			(effects
				(font
					(size 1.27 1.27)
				)
				(hide yes)
			)
		)
		(property "MPN" "GRM155R61H104KE14D"
			(at 69.85 218.44 0)
			(effects
				(font
					(size 1.27 1.27)
					(thickness 0.15)
				)
				(justify left bottom)
				(hide yes)
			)
		)
		(property "Val" "100n"
			(at 41.402 232.41 90)
			(effects
				(font
					(size 1.27 1.27)
					(thickness 0.15)
				)
				(justify right)
			)
		)
		(property "Voltage" "50V"
			(at 49.53 218.44 0)
			(effects
				(font
					(size 1.27 1.27)
					(thickness 0.15)
				)
				(justify left bottom)
				(hide yes)
			)
		)
		(property "Dielectric" "X5R"
			(at 52.07 218.44 0)
			(effects
				(font
					(size 1.27 1.27)
					(thickness 0.15)
				)
				(justify left bottom)
				(hide yes)
			)
		)
		(property "Manufacturer" "Murata"
			(at 54.61 218.44 0)
			(effects
				(font
					(size 1.27 1.27)
					(thickness 0.15)
				)
				(justify left bottom)
				(hide yes)
			)
		)
		(property "License" "Apache-2.0"
			(at 57.15 218.44 0)
			(effects
				(font
					(size 1.27 1.27)
					(thickness 0.15)
				)
				(justify left bottom)
				(hide yes)
			)
		)
		(property "Author" "Antmicro"
			(at 59.69 218.44 0)
			(effects
				(font
					(size 1.27 1.27)
					(thickness 0.15)
				)
				(justify left bottom)
				(hide yes)
			)
		)
		(pin "2"
		)
		(pin "1"
		)
		(instances
			(project "OCuLink to 10GbE adapter"
				(path ""
					(reference "C185")
					(unit 1)
				)
			)
		)
	)
	(symbol
		(lib_id "antmicroCapacitors0603:C_22u_16V_0603")
		(at 388.62 130.81 90)
		(unit 1)
		(exclude_from_sim no)
		(in_bom yes)
		(on_board yes)
		(dnp no)
		(fields_autoplaced yes)
		(property "Reference" "C155"
			(at 391.16 126.9936 90)
			(effects
				(font
					(size 1.27 1.27)
					(thickness 0.15)
				)
				(justify right)
			)
		)
		(property "Value" "C_22u_16V_0603"
			(at 398.78 110.49 0)
			(effects
				(font
					(size 1.27 1.27)
					(thickness 0.15)
				)
				(justify left bottom)
				(hide yes)
			)
		)
		(property "Footprint" "antmicro-footprints:C_0603_1608Metric_EIA"
			(at 401.32 110.49 0)
			(effects
				(font
					(size 1.27 1.27)
					(thickness 0.15)
				)
				(justify left bottom)
				(hide yes)
			)
		)
		(property "Datasheet" "https://product.samsungsem.com/mlcc/CL10A226MO7JZN.do"
			(at 403.86 110.49 0)
			(effects
				(font
					(size 1.27 1.27)
					(thickness 0.15)
				)
				(justify left bottom)
				(hide yes)
			)
		)
		(property "Description" "SMD Multilayer Ceramic Capacitor"
			(at 388.62 130.81 0)
			(effects
				(font
					(size 1.27 1.27)
				)
				(hide yes)
			)
		)
		(property "MPN" "CL10A226MO7JZNC"
			(at 406.4 110.49 0)
			(effects
				(font
					(size 1.27 1.27)
					(thickness 0.15)
				)
				(justify left bottom)
				(hide yes)
			)
		)
		(property "Manufacturer" "Samsung Electro-Mechanics"
			(at 408.94 110.49 0)
			(effects
				(font
					(size 1.27 1.27)
					(thickness 0.15)
				)
				(justify left bottom)
				(hide yes)
			)
		)
		(property "License" "Apache-2.0"
			(at 411.48 110.49 0)
			(effects
				(font
					(size 1.27 1.27)
					(thickness 0.15)
				)
				(justify left bottom)
				(hide yes)
			)
		)
		(property "Author" "Antmicro"
			(at 414.02 110.49 0)
			(effects
				(font
					(size 1.27 1.27)
					(thickness 0.15)
				)
				(justify left bottom)
				(hide yes)
			)
		)
		(property "Val" "22u"
			(at 391.16 129.5336 90)
			(effects
				(font
					(size 1.27 1.27)
					(thickness 0.15)
				)
				(justify right)
			)
		)
		(property "Voltage" "16V"
			(at 416.56 110.49 0)
			(effects
				(font
					(size 1.27 1.27)
				)
				(justify left bottom)
				(hide yes)
			)
		)
		(property "Dielectric" ""
			(at 419.1 110.49 0)
			(effects
				(font
					(size 1.27 1.27)
				)
				(justify left bottom)
				(hide yes)
			)
		)
		(pin "1"
		)
		(pin "2"
		)
		(instances
			(project "OCuLink to 10GbE adapter"
				(path ""
					(reference "C155")
					(unit 1)
				)
			)
		)
	)
	(symbol
		(lib_id "antmicropower:PWR_FLAG")
		(at 66.04 171.45 0)
		(unit 1)
		(exclude_from_sim no)
		(in_bom yes)
		(on_board yes)
		(dnp no)
		(fields_autoplaced yes)
		(property "Reference" "#FLG016"
			(at 66.04 169.545 0)
			(effects
				(font
					(size 1.27 1.27)
				)
				(hide yes)
			)
		)
		(property "Value" "PWR_FLAG"
			(at 66.04 166.37 0)
			(effects
				(font
					(size 1.27 1.27)
				)
			)
		)
		(property "Footprint" ""
			(at 66.04 171.45 0)
			(effects
				(font
					(size 1.27 1.27)
				)
				(hide yes)
			)
		)
		(property "Datasheet" ""
			(at 66.04 171.45 0)
			(effects
				(font
					(size 1.27 1.27)
				)
				(hide yes)
			)
		)
		(property "Description" ""
			(at 66.04 173.99 0)
			(effects
				(font
					(size 1.27 1.27)
				)
				(justify left bottom)
				(hide yes)
			)
		)
		(pin "1"
		)
		(instances
			(project "OCuLink to 10GbE adapter"
				(path ""
					(reference "#FLG016")
					(unit 1)
				)
			)
		)
	)
	(symbol
		(lib_id "antmicroCapacitors0402:C_1u_25V_0402")
		(at 388.62 52.07 90)
		(unit 1)
		(exclude_from_sim no)
		(in_bom yes)
		(on_board yes)
		(dnp no)
		(property "Reference" "C97"
			(at 390.652 48.26 90)
			(effects
				(font
					(size 1.27 1.27)
					(thickness 0.15)
				)
				(justify right)
			)
		)
		(property "Value" "C_1u_25V_0402"
			(at 398.78 31.75 0)
			(effects
				(font
					(size 1.27 1.27)
					(thickness 0.15)
				)
				(justify left bottom)
				(hide yes)
			)
		)
		(property "Footprint" "antmicro-footprints:C_0402_1005Metric"
			(at 401.32 31.75 0)
			(effects
				(font
					(size 1.27 1.27)
					(thickness 0.15)
				)
				(justify left bottom)
				(hide yes)
			)
		)
		(property "Datasheet" "https://www.murata.com/products/productdetail?partno=GRM155R61E105KE11%23"
			(at 403.86 31.75 0)
			(effects
				(font
					(size 1.27 1.27)
					(thickness 0.15)
				)
				(justify left bottom)
				(hide yes)
			)
		)
		(property "Description" "SMD Multilayer Ceramic Capacitor, 1 µF, 25 V, 0402 [1005 Metric], ± 10%, X5R, GRM Series"
			(at 388.62 52.07 0)
			(effects
				(font
					(size 1.27 1.27)
				)
				(hide yes)
			)
		)
		(property "MPN" "GRM155R61E105KE11J"
			(at 406.4 31.75 0)
			(effects
				(font
					(size 1.27 1.27)
					(thickness 0.15)
				)
				(justify left bottom)
				(hide yes)
			)
		)
		(property "Manufacturer" "Murata"
			(at 408.94 31.75 0)
			(effects
				(font
					(size 1.27 1.27)
					(thickness 0.15)
				)
				(justify left bottom)
				(hide yes)
			)
		)
		(property "License" "Apache-2.0"
			(at 411.48 31.75 0)
			(effects
				(font
					(size 1.27 1.27)
					(thickness 0.15)
				)
				(justify left bottom)
				(hide yes)
			)
		)
		(property "Author" "Antmicro"
			(at 414.02 31.75 0)
			(effects
				(font
					(size 1.27 1.27)
					(thickness 0.15)
				)
				(justify left bottom)
				(hide yes)
			)
		)
		(property "Val" "1u"
			(at 390.652 50.8 90)
			(effects
				(font
					(size 1.27 1.27)
					(thickness 0.15)
				)
				(justify right)
			)
		)
		(property "Voltage" "25V"
			(at 416.56 31.75 0)
			(effects
				(font
					(size 1.27 1.27)
				)
				(justify left bottom)
				(hide yes)
			)
		)
		(property "Dielectric" "X5R"
			(at 419.1 31.75 0)
			(effects
				(font
					(size 1.27 1.27)
				)
				(justify left bottom)
				(hide yes)
			)
		)
		(pin "2"
		)
		(pin "1"
		)
		(instances
			(project "OCuLink to 10GbE adapter"
				(path ""
					(reference "C97")
					(unit 1)
				)
			)
		)
	)
	(symbol
		(lib_id "antmicropower:GND")
		(at 54.61 236.22 0)
		(unit 1)
		(exclude_from_sim no)
		(in_bom yes)
		(on_board yes)
		(dnp no)
		(property "Reference" "#PWR0240"
			(at 63.5 238.76 0)
			(effects
				(font
					(size 1.27 1.27)
					(thickness 0.15)
				)
				(justify left bottom)
				(hide yes)
			)
		)
		(property "Value" "GND"
			(at 54.61 240.03 0)
			(effects
				(font
					(size 1.27 1.27)
					(thickness 0.15)
				)
			)
		)
		(property "Footprint" ""
			(at 63.5 243.84 0)
			(effects
				(font
					(size 1.27 1.27)
					(thickness 0.15)
				)
				(justify left bottom)
				(hide yes)
			)
		)
		(property "Datasheet" ""
			(at 63.5 248.92 0)
			(effects
				(font
					(size 1.27 1.27)
					(thickness 0.15)
				)
				(justify left bottom)
				(hide yes)
			)
		)
		(property "Description" ""
			(at 54.61 236.22 0)
			(effects
				(font
					(size 1.27 1.27)
				)
				(hide yes)
			)
		)
		(property "Author" "Antmicro"
			(at 63.5 243.84 0)
			(effects
				(font
					(size 1.27 1.27)
					(thickness 0.15)
				)
				(justify left bottom)
				(hide yes)
			)
		)
		(property "License" "Apache-2.0"
			(at 63.5 246.38 0)
			(effects
				(font
					(size 1.27 1.27)
					(thickness 0.15)
				)
				(justify left bottom)
				(hide yes)
			)
		)
		(pin "1"
		)
		(instances
			(project "OCuLink to 10GbE adapter"
				(path ""
					(reference "#PWR0240")
					(unit 1)
				)
			)
		)
	)
	(symbol
		(lib_id "antmicropower:GND")
		(at 326.39 54.61 0)
		(unit 1)
		(exclude_from_sim no)
		(in_bom yes)
		(on_board yes)
		(dnp no)
		(property "Reference" "#PWR0124"
			(at 335.28 57.15 0)
			(effects
				(font
					(size 1.27 1.27)
					(thickness 0.15)
				)
				(justify left bottom)
				(hide yes)
			)
		)
		(property "Value" "GND"
			(at 326.39 58.42 0)
			(effects
				(font
					(size 1.27 1.27)
					(thickness 0.15)
				)
			)
		)
		(property "Footprint" ""
			(at 335.28 62.23 0)
			(effects
				(font
					(size 1.27 1.27)
					(thickness 0.15)
				)
				(justify left bottom)
				(hide yes)
			)
		)
		(property "Datasheet" ""
			(at 335.28 67.31 0)
			(effects
				(font
					(size 1.27 1.27)
					(thickness 0.15)
				)
				(justify left bottom)
				(hide yes)
			)
		)
		(property "Description" ""
			(at 326.39 54.61 0)
			(effects
				(font
					(size 1.27 1.27)
				)
				(hide yes)
			)
		)
		(property "Author" "Antmicro"
			(at 335.28 62.23 0)
			(effects
				(font
					(size 1.27 1.27)
					(thickness 0.15)
				)
				(justify left bottom)
				(hide yes)
			)
		)
		(property "License" "Apache-2.0"
			(at 335.28 64.77 0)
			(effects
				(font
					(size 1.27 1.27)
					(thickness 0.15)
				)
				(justify left bottom)
				(hide yes)
			)
		)
		(pin "1"
		)
		(instances
			(project "OCuLink to 10GbE adapter"
				(path ""
					(reference "#PWR0124")
					(unit 1)
				)
			)
		)
	)
	(symbol
		(lib_id "antmicropower:GND")
		(at 106.68 76.2 0)
		(unit 1)
		(exclude_from_sim no)
		(in_bom yes)
		(on_board yes)
		(dnp no)
		(property "Reference" "#PWR0137"
			(at 115.57 78.74 0)
			(effects
				(font
					(size 1.27 1.27)
					(thickness 0.15)
				)
				(justify left bottom)
				(hide yes)
			)
		)
		(property "Value" "GND"
			(at 106.68 80.01 0)
			(effects
				(font
					(size 1.27 1.27)
					(thickness 0.15)
				)
			)
		)
		(property "Footprint" ""
			(at 115.57 83.82 0)
			(effects
				(font
					(size 1.27 1.27)
					(thickness 0.15)
				)
				(justify left bottom)
				(hide yes)
			)
		)
		(property "Datasheet" ""
			(at 115.57 88.9 0)
			(effects
				(font
					(size 1.27 1.27)
					(thickness 0.15)
				)
				(justify left bottom)
				(hide yes)
			)
		)
		(property "Description" ""
			(at 106.68 76.2 0)
			(effects
				(font
					(size 1.27 1.27)
				)
				(hide yes)
			)
		)
		(property "Author" "Antmicro"
			(at 115.57 83.82 0)
			(effects
				(font
					(size 1.27 1.27)
					(thickness 0.15)
				)
				(justify left bottom)
				(hide yes)
			)
		)
		(property "License" "Apache-2.0"
			(at 115.57 86.36 0)
			(effects
				(font
					(size 1.27 1.27)
					(thickness 0.15)
				)
				(justify left bottom)
				(hide yes)
			)
		)
		(pin "1"
		)
		(instances
			(project "OCuLink to 10GbE adapter"
				(path ""
					(reference "#PWR0137")
					(unit 1)
				)
			)
		)
	)
	(symbol
		(lib_id "antmicropower:PWR_FLAG")
		(at 66.04 118.11 0)
		(unit 1)
		(exclude_from_sim no)
		(in_bom yes)
		(on_board yes)
		(dnp no)
		(fields_autoplaced yes)
		(property "Reference" "#FLG013"
			(at 66.04 116.205 0)
			(effects
				(font
					(size 1.27 1.27)
				)
				(hide yes)
			)
		)
		(property "Value" "PWR_FLAG"
			(at 66.04 113.03 0)
			(effects
				(font
					(size 1.27 1.27)
				)
			)
		)
		(property "Footprint" ""
			(at 66.04 118.11 0)
			(effects
				(font
					(size 1.27 1.27)
				)
				(hide yes)
			)
		)
		(property "Datasheet" ""
			(at 66.04 118.11 0)
			(effects
				(font
					(size 1.27 1.27)
				)
				(hide yes)
			)
		)
		(property "Description" ""
			(at 66.04 120.65 0)
			(effects
				(font
					(size 1.27 1.27)
				)
				(justify left bottom)
				(hide yes)
			)
		)
		(pin "1"
		)
		(instances
			(project "OCuLink to 10GbE adapter"
				(path ""
					(reference "#FLG013")
					(unit 1)
				)
			)
		)
	)
	(symbol
		(lib_id "antmicropower:GND")
		(at 299.72 54.61 0)
		(unit 1)
		(exclude_from_sim no)
		(in_bom yes)
		(on_board yes)
		(dnp no)
		(property "Reference" "#PWR0121"
			(at 308.61 57.15 0)
			(effects
				(font
					(size 1.27 1.27)
					(thickness 0.15)
				)
				(justify left bottom)
				(hide yes)
			)
		)
		(property "Value" "GND"
			(at 299.72 58.42 0)
			(effects
				(font
					(size 1.27 1.27)
					(thickness 0.15)
				)
			)
		)
		(property "Footprint" ""
			(at 308.61 62.23 0)
			(effects
				(font
					(size 1.27 1.27)
					(thickness 0.15)
				)
				(justify left bottom)
				(hide yes)
			)
		)
		(property "Datasheet" ""
			(at 308.61 67.31 0)
			(effects
				(font
					(size 1.27 1.27)
					(thickness 0.15)
				)
				(justify left bottom)
				(hide yes)
			)
		)
		(property "Description" ""
			(at 299.72 54.61 0)
			(effects
				(font
					(size 1.27 1.27)
				)
				(hide yes)
			)
		)
		(property "Author" "Antmicro"
			(at 308.61 62.23 0)
			(effects
				(font
					(size 1.27 1.27)
					(thickness 0.15)
				)
				(justify left bottom)
				(hide yes)
			)
		)
		(property "License" "Apache-2.0"
			(at 308.61 64.77 0)
			(effects
				(font
					(size 1.27 1.27)
					(thickness 0.15)
				)
				(justify left bottom)
				(hide yes)
			)
		)
		(pin "1"
		)
		(instances
			(project "OCuLink to 10GbE adapter"
				(path ""
					(reference "#PWR0121")
					(unit 1)
				)
			)
		)
	)
	(symbol
		(lib_id "antmicropower:GND")
		(at 309.88 152.4 0)
		(unit 1)
		(exclude_from_sim no)
		(in_bom yes)
		(on_board yes)
		(dnp no)
		(property "Reference" "#PWR0210"
			(at 318.77 154.94 0)
			(effects
				(font
					(size 1.27 1.27)
					(thickness 0.15)
				)
				(justify left bottom)
				(hide yes)
			)
		)
		(property "Value" "GND"
			(at 309.88 156.21 0)
			(effects
				(font
					(size 1.27 1.27)
					(thickness 0.15)
				)
			)
		)
		(property "Footprint" ""
			(at 318.77 160.02 0)
			(effects
				(font
					(size 1.27 1.27)
					(thickness 0.15)
				)
				(justify left bottom)
				(hide yes)
			)
		)
		(property "Datasheet" ""
			(at 318.77 165.1 0)
			(effects
				(font
					(size 1.27 1.27)
					(thickness 0.15)
				)
				(justify left bottom)
				(hide yes)
			)
		)
		(property "Description" ""
			(at 309.88 152.4 0)
			(effects
				(font
					(size 1.27 1.27)
				)
				(hide yes)
			)
		)
		(property "Author" "Antmicro"
			(at 318.77 160.02 0)
			(effects
				(font
					(size 1.27 1.27)
					(thickness 0.15)
				)
				(justify left bottom)
				(hide yes)
			)
		)
		(property "License" "Apache-2.0"
			(at 318.77 162.56 0)
			(effects
				(font
					(size 1.27 1.27)
					(thickness 0.15)
				)
				(justify left bottom)
				(hide yes)
			)
		)
		(pin "1"
		)
		(instances
			(project "OCuLink to 10GbE adapter"
				(path ""
					(reference "#PWR0210")
					(unit 1)
				)
			)
		)
	)
	(symbol
		(lib_id "antmicroCapacitorspol:C_Pol_470u_6.3V_Vishay-TR3-D")
		(at 33.02 46.99 270)
		(unit 1)
		(exclude_from_sim no)
		(in_bom yes)
		(on_board yes)
		(dnp no)
		(property "Reference" "C78"
			(at 35.306 47.752 90)
			(effects
				(font
					(size 1.27 1.27)
					(thickness 0.15)
				)
				(justify left)
			)
		)
		(property "Value" "C_Pol_470u_6.3V_Vishay-TR3-D"
			(at 30.48 60.96 0)
			(effects
				(font
					(size 1.27 1.27)
					(thickness 0.15)
				)
				(justify left bottom)
				(hide yes)
			)
		)
		(property "Footprint" "antmicro-footprints:C_Pol_EIA-D"
			(at 25.4 60.96 0)
			(effects
				(font
					(size 1.27 1.27)
					(thickness 0.15)
				)
				(justify left bottom)
				(hide yes)
			)
		)
		(property "Datasheet" "https://www.vishay.com/docs/40080/tr3.pdf"
			(at 22.86 60.96 0)
			(effects
				(font
					(size 1.27 1.27)
					(thickness 0.15)
				)
				(justify left bottom)
				(hide yes)
			)
		)
		(property "Description" "470 µF Molded Tantalum Capacitors 6.3 V 2917 (7343 Metric) 200mOhm"
			(at 33.02 46.99 0)
			(effects
				(font
					(size 1.27 1.27)
				)
				(hide yes)
			)
		)
		(property "Val" "470u"
			(at 35.306 50.292 90)
			(effects
				(font
					(size 1.27 1.27)
					(thickness 0.15)
				)
				(justify left)
			)
		)
		(property "MPN" "TR3D477M6R3C0200"
			(at 20.32 60.96 0)
			(effects
				(font
					(size 1.27 1.27)
					(thickness 0.15)
				)
				(justify left bottom)
				(hide yes)
			)
		)
		(property "Manufacturer" "Vishay"
			(at 17.78 60.96 0)
			(effects
				(font
					(size 1.27 1.27)
					(thickness 0.15)
				)
				(justify left bottom)
				(hide yes)
			)
		)
		(property "License" "Apache-2.0"
			(at 15.24 60.96 0)
			(effects
				(font
					(size 1.27 1.27)
					(thickness 0.15)
				)
				(justify left bottom)
				(hide yes)
			)
		)
		(property "Author" "Antmicro"
			(at 12.7 60.96 0)
			(effects
				(font
					(size 1.27 1.27)
					(thickness 0.15)
				)
				(justify left bottom)
				(hide yes)
			)
		)
		(property "Voltage" "6.3V"
			(at 10.16 60.96 0)
			(effects
				(font
					(size 1.27 1.27)
				)
				(justify left bottom)
				(hide yes)
			)
		)
		(property "Dielectric" "template_dielectric"
			(at 7.62 60.96 0)
			(effects
				(font
					(size 1.27 1.27)
				)
				(justify left bottom)
				(hide yes)
			)
		)
		(pin "2"
		)
		(pin "1"
		)
		(instances
			(project ""
				(path ""
					(reference "C78")
					(unit 1)
				)
			)
		)
	)
	(symbol
		(lib_id "antmicropower:GND")
		(at 361.95 115.57 0)
		(unit 1)
		(exclude_from_sim no)
		(in_bom yes)
		(on_board yes)
		(dnp no)
		(property "Reference" "#PWR0184"
			(at 370.84 118.11 0)
			(effects
				(font
					(size 1.27 1.27)
					(thickness 0.15)
				)
				(justify left bottom)
				(hide yes)
			)
		)
		(property "Value" "GND"
			(at 361.95 119.38 0)
			(effects
				(font
					(size 1.27 1.27)
					(thickness 0.15)
				)
			)
		)
		(property "Footprint" ""
			(at 370.84 123.19 0)
			(effects
				(font
					(size 1.27 1.27)
					(thickness 0.15)
				)
				(justify left bottom)
				(hide yes)
			)
		)
		(property "Datasheet" ""
			(at 370.84 128.27 0)
			(effects
				(font
					(size 1.27 1.27)
					(thickness 0.15)
				)
				(justify left bottom)
				(hide yes)
			)
		)
		(property "Description" ""
			(at 361.95 115.57 0)
			(effects
				(font
					(size 1.27 1.27)
				)
				(hide yes)
			)
		)
		(property "Author" "Antmicro"
			(at 370.84 123.19 0)
			(effects
				(font
					(size 1.27 1.27)
					(thickness 0.15)
				)
				(justify left bottom)
				(hide yes)
			)
		)
		(property "License" "Apache-2.0"
			(at 370.84 125.73 0)
			(effects
				(font
					(size 1.27 1.27)
					(thickness 0.15)
				)
				(justify left bottom)
				(hide yes)
			)
		)
		(pin "1"
		)
		(instances
			(project "OCuLink to 10GbE adapter"
				(path ""
					(reference "#PWR0184")
					(unit 1)
				)
			)
		)
	)
	(symbol
		(lib_id "antmicroCapacitors0603:C_10u_10V_X7R_0603")
		(at 300.99 149.86 270)
		(mirror x)
		(unit 1)
		(exclude_from_sim no)
		(in_bom yes)
		(on_board yes)
		(dnp no)
		(property "Reference" "C159"
			(at 298.958 146.05 90)
			(effects
				(font
					(size 1.27 1.27)
					(thickness 0.15)
				)
				(justify right)
			)
		)
		(property "Value" "C_10u_10V_X7R_0603"
			(at 290.83 134.62 0)
			(effects
				(font
					(size 1.27 1.27)
					(thickness 0.15)
				)
				(justify left bottom)
				(hide yes)
			)
		)
		(property "Footprint" "antmicro-footprints:C_0603_1608Metric"
			(at 288.29 134.62 0)
			(effects
				(font
					(size 1.27 1.27)
					(thickness 0.15)
				)
				(justify left bottom)
				(hide yes)
			)
		)
		(property "Datasheet" "https://www.murata.com/products/productdetail?partno=GRM188Z71A106KA73%23"
			(at 285.75 134.62 0)
			(effects
				(font
					(size 1.27 1.27)
					(thickness 0.15)
				)
				(justify left bottom)
				(hide yes)
			)
		)
		(property "Description" "SMD Multilayer Ceramic Capacitor,  10µF, 10V, 0603, ±10%, X7R"
			(at 300.99 149.86 0)
			(effects
				(font
					(size 1.27 1.27)
				)
				(hide yes)
			)
		)
		(property "MPN" "GRM188Z71A106KA73D"
			(at 283.21 134.62 0)
			(effects
				(font
					(size 1.27 1.27)
					(thickness 0.15)
				)
				(justify left bottom)
				(hide yes)
			)
		)
		(property "Val" "10u"
			(at 298.958 148.59 90)
			(effects
				(font
					(size 1.27 1.27)
					(thickness 0.15)
				)
				(justify right)
			)
		)
		(property "Voltage" "10V"
			(at 280.67 134.62 0)
			(effects
				(font
					(size 1.27 1.27)
					(thickness 0.15)
				)
				(justify left bottom)
				(hide yes)
			)
		)
		(property "Dielectric" "X7R"
			(at 278.13 134.62 0)
			(effects
				(font
					(size 1.27 1.27)
					(thickness 0.15)
				)
				(justify left bottom)
				(hide yes)
			)
		)
		(property "Manufacturer" "Murata"
			(at 275.59 134.62 0)
			(effects
				(font
					(size 1.27 1.27)
					(thickness 0.15)
				)
				(justify left bottom)
				(hide yes)
			)
		)
		(property "License" "Apache-2.0"
			(at 273.05 134.62 0)
			(effects
				(font
					(size 1.27 1.27)
					(thickness 0.15)
				)
				(justify left bottom)
				(hide yes)
			)
		)
		(property "Author" "Antmicro"
			(at 270.51 134.62 0)
			(effects
				(font
					(size 1.27 1.27)
					(thickness 0.15)
				)
				(justify left bottom)
				(hide yes)
			)
		)
		(pin "1"
		)
		(pin "2"
		)
		(instances
			(project "OCuLink to 10GbE adapter"
				(path ""
					(reference "C159")
					(unit 1)
				)
			)
		)
	)
	(symbol
		(lib_id "antmicroCapacitors0402:C_1u_25V_0402")
		(at 353.06 52.07 90)
		(unit 1)
		(exclude_from_sim no)
		(in_bom yes)
		(on_board yes)
		(dnp no)
		(property "Reference" "C93"
			(at 355.092 48.26 90)
			(effects
				(font
					(size 1.27 1.27)
					(thickness 0.15)
				)
				(justify right)
			)
		)
		(property "Value" "C_1u_25V_0402"
			(at 363.22 31.75 0)
			(effects
				(font
					(size 1.27 1.27)
					(thickness 0.15)
				)
				(justify left bottom)
				(hide yes)
			)
		)
		(property "Footprint" "antmicro-footprints:C_0402_1005Metric"
			(at 365.76 31.75 0)
			(effects
				(font
					(size 1.27 1.27)
					(thickness 0.15)
				)
				(justify left bottom)
				(hide yes)
			)
		)
		(property "Datasheet" "https://www.murata.com/products/productdetail?partno=GRM155R61E105KE11%23"
			(at 368.3 31.75 0)
			(effects
				(font
					(size 1.27 1.27)
					(thickness 0.15)
				)
				(justify left bottom)
				(hide yes)
			)
		)
		(property "Description" "SMD Multilayer Ceramic Capacitor, 1 µF, 25 V, 0402 [1005 Metric], ± 10%, X5R, GRM Series"
			(at 353.06 52.07 0)
			(effects
				(font
					(size 1.27 1.27)
				)
				(hide yes)
			)
		)
		(property "MPN" "GRM155R61E105KE11J"
			(at 370.84 31.75 0)
			(effects
				(font
					(size 1.27 1.27)
					(thickness 0.15)
				)
				(justify left bottom)
				(hide yes)
			)
		)
		(property "Manufacturer" "Murata"
			(at 373.38 31.75 0)
			(effects
				(font
					(size 1.27 1.27)
					(thickness 0.15)
				)
				(justify left bottom)
				(hide yes)
			)
		)
		(property "License" "Apache-2.0"
			(at 375.92 31.75 0)
			(effects
				(font
					(size 1.27 1.27)
					(thickness 0.15)
				)
				(justify left bottom)
				(hide yes)
			)
		)
		(property "Author" "Antmicro"
			(at 378.46 31.75 0)
			(effects
				(font
					(size 1.27 1.27)
					(thickness 0.15)
				)
				(justify left bottom)
				(hide yes)
			)
		)
		(property "Val" "1u"
			(at 355.092 50.8 90)
			(effects
				(font
					(size 1.27 1.27)
					(thickness 0.15)
				)
				(justify right)
			)
		)
		(property "Voltage" "25V"
			(at 381 31.75 0)
			(effects
				(font
					(size 1.27 1.27)
				)
				(justify left bottom)
				(hide yes)
			)
		)
		(property "Dielectric" "X5R"
			(at 383.54 31.75 0)
			(effects
				(font
					(size 1.27 1.27)
				)
				(justify left bottom)
				(hide yes)
			)
		)
		(pin "2"
		)
		(pin "1"
		)
		(instances
			(project "OCuLink to 10GbE adapter"
				(path ""
					(reference "C93")
					(unit 1)
				)
			)
		)
	)
	(symbol
		(lib_id "antmicroCapacitors0402:C_1u_25V_0402")
		(at 80.01 52.07 90)
		(unit 1)
		(exclude_from_sim no)
		(in_bom yes)
		(on_board yes)
		(dnp no)
		(property "Reference" "C82"
			(at 82.042 48.26 90)
			(effects
				(font
					(size 1.27 1.27)
					(thickness 0.15)
				)
				(justify right)
			)
		)
		(property "Value" "C_1u_25V_0402"
			(at 90.17 31.75 0)
			(effects
				(font
					(size 1.27 1.27)
					(thickness 0.15)
				)
				(justify left bottom)
				(hide yes)
			)
		)
		(property "Footprint" "antmicro-footprints:C_0402_1005Metric"
			(at 92.71 31.75 0)
			(effects
				(font
					(size 1.27 1.27)
					(thickness 0.15)
				)
				(justify left bottom)
				(hide yes)
			)
		)
		(property "Datasheet" "https://www.murata.com/products/productdetail?partno=GRM155R61E105KE11%23"
			(at 95.25 31.75 0)
			(effects
				(font
					(size 1.27 1.27)
					(thickness 0.15)
				)
				(justify left bottom)
				(hide yes)
			)
		)
		(property "Description" "SMD Multilayer Ceramic Capacitor, 1 µF, 25 V, 0402 [1005 Metric], ± 10%, X5R, GRM Series"
			(at 80.01 52.07 0)
			(effects
				(font
					(size 1.27 1.27)
				)
				(hide yes)
			)
		)
		(property "MPN" "GRM155R61E105KE11J"
			(at 97.79 31.75 0)
			(effects
				(font
					(size 1.27 1.27)
					(thickness 0.15)
				)
				(justify left bottom)
				(hide yes)
			)
		)
		(property "Manufacturer" "Murata"
			(at 100.33 31.75 0)
			(effects
				(font
					(size 1.27 1.27)
					(thickness 0.15)
				)
				(justify left bottom)
				(hide yes)
			)
		)
		(property "License" "Apache-2.0"
			(at 102.87 31.75 0)
			(effects
				(font
					(size 1.27 1.27)
					(thickness 0.15)
				)
				(justify left bottom)
				(hide yes)
			)
		)
		(property "Author" "Antmicro"
			(at 105.41 31.75 0)
			(effects
				(font
					(size 1.27 1.27)
					(thickness 0.15)
				)
				(justify left bottom)
				(hide yes)
			)
		)
		(property "Val" "1u"
			(at 82.042 50.8 90)
			(effects
				(font
					(size 1.27 1.27)
					(thickness 0.15)
				)
				(justify right)
			)
		)
		(property "Voltage" "25V"
			(at 107.95 31.75 0)
			(effects
				(font
					(size 1.27 1.27)
				)
				(justify left bottom)
				(hide yes)
			)
		)
		(property "Dielectric" "X5R"
			(at 110.49 31.75 0)
			(effects
				(font
					(size 1.27 1.27)
				)
				(justify left bottom)
				(hide yes)
			)
		)
		(pin "2"
		)
		(pin "1"
		)
		(instances
			(project "OCuLink to 10GbE adapter"
				(path ""
					(reference "C82")
					(unit 1)
				)
			)
		)
	)
	(symbol
		(lib_id "antmicropower:GND")
		(at 106.68 209.55 0)
		(unit 1)
		(exclude_from_sim no)
		(in_bom yes)
		(on_board yes)
		(dnp no)
		(property "Reference" "#PWR0236"
			(at 115.57 212.09 0)
			(effects
				(font
					(size 1.27 1.27)
					(thickness 0.15)
				)
				(justify left bottom)
				(hide yes)
			)
		)
		(property "Value" "GND"
			(at 106.68 213.36 0)
			(effects
				(font
					(size 1.27 1.27)
					(thickness 0.15)
				)
			)
		)
		(property "Footprint" ""
			(at 115.57 217.17 0)
			(effects
				(font
					(size 1.27 1.27)
					(thickness 0.15)
				)
				(justify left bottom)
				(hide yes)
			)
		)
		(property "Datasheet" ""
			(at 115.57 222.25 0)
			(effects
				(font
					(size 1.27 1.27)
					(thickness 0.15)
				)
				(justify left bottom)
				(hide yes)
			)
		)
		(property "Description" ""
			(at 106.68 209.55 0)
			(effects
				(font
					(size 1.27 1.27)
				)
				(hide yes)
			)
		)
		(property "Author" "Antmicro"
			(at 115.57 217.17 0)
			(effects
				(font
					(size 1.27 1.27)
					(thickness 0.15)
				)
				(justify left bottom)
				(hide yes)
			)
		)
		(property "License" "Apache-2.0"
			(at 115.57 219.71 0)
			(effects
				(font
					(size 1.27 1.27)
					(thickness 0.15)
				)
				(justify left bottom)
				(hide yes)
			)
		)
		(pin "1"
		)
		(instances
			(project "OCuLink to 10GbE adapter"
				(path ""
					(reference "#PWR0236")
					(unit 1)
				)
			)
		)
	)
	(symbol
		(lib_id "antmicropower:VCC")
		(at 283.21 115.57 0)
		(unit 1)
		(exclude_from_sim no)
		(in_bom yes)
		(on_board yes)
		(dnp no)
		(property "Reference" "#PWR0177"
			(at 283.21 119.38 0)
			(effects
				(font
					(size 1.27 1.27)
				)
				(hide yes)
			)
		)
		(property "Value" "VCCA"
			(at 283.21 111.76 0)
			(effects
				(font
					(size 1.27 1.27)
				)
			)
		)
		(property "Footprint" ""
			(at 283.21 115.57 0)
			(effects
				(font
					(size 1.27 1.27)
				)
				(hide yes)
			)
		)
		(property "Datasheet" ""
			(at 283.21 115.57 0)
			(effects
				(font
					(size 1.27 1.27)
				)
				(hide yes)
			)
		)
		(property "Description" ""
			(at 283.21 115.57 0)
			(effects
				(font
					(size 1.27 1.27)
				)
				(hide yes)
			)
		)
		(pin "1"
		)
		(instances
			(project "OCuLink to 10GbE adapter"
				(path ""
					(reference "#PWR0177")
					(unit 1)
				)
			)
		)
	)
	(symbol
		(lib_id "antmicropower:GND")
		(at 71.12 182.88 0)
		(unit 1)
		(exclude_from_sim no)
		(in_bom yes)
		(on_board yes)
		(dnp no)
		(property "Reference" "#PWR0226"
			(at 80.01 185.42 0)
			(effects
				(font
					(size 1.27 1.27)
					(thickness 0.15)
				)
				(justify left bottom)
				(hide yes)
			)
		)
		(property "Value" "GND"
			(at 71.12 186.69 0)
			(effects
				(font
					(size 1.27 1.27)
					(thickness 0.15)
				)
			)
		)
		(property "Footprint" ""
			(at 80.01 190.5 0)
			(effects
				(font
					(size 1.27 1.27)
					(thickness 0.15)
				)
				(justify left bottom)
				(hide yes)
			)
		)
		(property "Datasheet" ""
			(at 80.01 195.58 0)
			(effects
				(font
					(size 1.27 1.27)
					(thickness 0.15)
				)
				(justify left bottom)
				(hide yes)
			)
		)
		(property "Description" ""
			(at 71.12 182.88 0)
			(effects
				(font
					(size 1.27 1.27)
				)
				(hide yes)
			)
		)
		(property "Author" "Antmicro"
			(at 80.01 190.5 0)
			(effects
				(font
					(size 1.27 1.27)
					(thickness 0.15)
				)
				(justify left bottom)
				(hide yes)
			)
		)
		(property "License" "Apache-2.0"
			(at 80.01 193.04 0)
			(effects
				(font
					(size 1.27 1.27)
					(thickness 0.15)
				)
				(justify left bottom)
				(hide yes)
			)
		)
		(pin "1"
		)
		(instances
			(project "OCuLink to 10GbE adapter"
				(path ""
					(reference "#PWR0226")
					(unit 1)
				)
			)
		)
	)
	(symbol
		(lib_id "antmicropower:+1V8")
		(at 21.59 90.17 0)
		(unit 1)
		(exclude_from_sim no)
		(in_bom yes)
		(on_board yes)
		(dnp no)
		(property "Reference" "#PWR0163"
			(at 36.83 92.71 0)
			(effects
				(font
					(size 1.27 1.27)
					(thickness 0.15)
				)
				(justify left bottom)
				(hide yes)
			)
		)
		(property "Value" "+1V88"
			(at 21.59 86.36 0)
			(effects
				(font
					(size 1.27 1.27)
					(thickness 0.15)
				)
			)
		)
		(property "Footprint" ""
			(at 36.83 97.79 0)
			(effects
				(font
					(size 1.27 1.27)
					(thickness 0.15)
				)
				(justify left bottom)
				(hide yes)
			)
		)
		(property "Datasheet" ""
			(at 36.83 100.33 0)
			(effects
				(font
					(size 1.27 1.27)
					(thickness 0.15)
				)
				(justify left bottom)
				(hide yes)
			)
		)
		(property "Description" ""
			(at 21.59 90.17 0)
			(effects
				(font
					(size 1.27 1.27)
				)
				(hide yes)
			)
		)
		(property "Author" "Antmicro"
			(at 36.83 95.25 0)
			(effects
				(font
					(size 1.27 1.27)
					(thickness 0.15)
				)
				(justify left bottom)
				(hide yes)
			)
		)
		(property "License" "Apache-2.0"
			(at 36.83 97.79 0)
			(effects
				(font
					(size 1.27 1.27)
					(thickness 0.15)
				)
				(justify left bottom)
				(hide yes)
			)
		)
		(pin "1"
		)
		(instances
			(project "OCuLink to 10GbE adapter"
				(path ""
					(reference "#PWR0163")
					(unit 1)
				)
			)
		)
	)
	(symbol
		(lib_id "antmicropower:GND")
		(at 41.91 182.88 0)
		(unit 1)
		(exclude_from_sim no)
		(in_bom yes)
		(on_board yes)
		(dnp no)
		(property "Reference" "#PWR0223"
			(at 50.8 185.42 0)
			(effects
				(font
					(size 1.27 1.27)
					(thickness 0.15)
				)
				(justify left bottom)
				(hide yes)
			)
		)
		(property "Value" "GND"
			(at 41.91 186.69 0)
			(effects
				(font
					(size 1.27 1.27)
					(thickness 0.15)
				)
			)
		)
		(property "Footprint" ""
			(at 50.8 190.5 0)
			(effects
				(font
					(size 1.27 1.27)
					(thickness 0.15)
				)
				(justify left bottom)
				(hide yes)
			)
		)
		(property "Datasheet" ""
			(at 50.8 195.58 0)
			(effects
				(font
					(size 1.27 1.27)
					(thickness 0.15)
				)
				(justify left bottom)
				(hide yes)
			)
		)
		(property "Description" ""
			(at 41.91 182.88 0)
			(effects
				(font
					(size 1.27 1.27)
				)
				(hide yes)
			)
		)
		(property "Author" "Antmicro"
			(at 50.8 190.5 0)
			(effects
				(font
					(size 1.27 1.27)
					(thickness 0.15)
				)
				(justify left bottom)
				(hide yes)
			)
		)
		(property "License" "Apache-2.0"
			(at 50.8 193.04 0)
			(effects
				(font
					(size 1.27 1.27)
					(thickness 0.15)
				)
				(justify left bottom)
				(hide yes)
			)
		)
		(pin "1"
		)
		(instances
			(project "OCuLink to 10GbE adapter"
				(path ""
					(reference "#PWR0223")
					(unit 1)
				)
			)
		)
	)
	(symbol
		(lib_id "antmicropower:GND")
		(at 54.61 262.89 0)
		(unit 1)
		(exclude_from_sim no)
		(in_bom yes)
		(on_board yes)
		(dnp no)
		(property "Reference" "#PWR0244"
			(at 63.5 265.43 0)
			(effects
				(font
					(size 1.27 1.27)
					(thickness 0.15)
				)
				(justify left bottom)
				(hide yes)
			)
		)
		(property "Value" "GND"
			(at 54.61 266.7 0)
			(effects
				(font
					(size 1.27 1.27)
					(thickness 0.15)
				)
			)
		)
		(property "Footprint" ""
			(at 63.5 270.51 0)
			(effects
				(font
					(size 1.27 1.27)
					(thickness 0.15)
				)
				(justify left bottom)
				(hide yes)
			)
		)
		(property "Datasheet" ""
			(at 63.5 275.59 0)
			(effects
				(font
					(size 1.27 1.27)
					(thickness 0.15)
				)
				(justify left bottom)
				(hide yes)
			)
		)
		(property "Description" ""
			(at 54.61 262.89 0)
			(effects
				(font
					(size 1.27 1.27)
				)
				(hide yes)
			)
		)
		(property "Author" "Antmicro"
			(at 63.5 270.51 0)
			(effects
				(font
					(size 1.27 1.27)
					(thickness 0.15)
				)
				(justify left bottom)
				(hide yes)
			)
		)
		(property "License" "Apache-2.0"
			(at 63.5 273.05 0)
			(effects
				(font
					(size 1.27 1.27)
					(thickness 0.15)
				)
				(justify left bottom)
				(hide yes)
			)
		)
		(pin "1"
		)
		(instances
			(project "OCuLink to 10GbE adapter"
				(path ""
					(reference "#PWR0244")
					(unit 1)
				)
			)
		)
	)
	(symbol
		(lib_id "antmicropower:VDD")
		(at 186.69 78.74 0)
		(unit 1)
		(exclude_from_sim no)
		(in_bom yes)
		(on_board yes)
		(dnp no)
		(property "Reference" "#PWR0156"
			(at 186.69 82.55 0)
			(effects
				(font
					(size 1.27 1.27)
				)
				(hide yes)
			)
		)
		(property "Value" "AVDDH"
			(at 186.69 74.93 0)
			(effects
				(font
					(size 1.27 1.27)
				)
			)
		)
		(property "Footprint" ""
			(at 186.69 78.74 0)
			(effects
				(font
					(size 1.27 1.27)
				)
				(hide yes)
			)
		)
		(property "Datasheet" ""
			(at 186.69 78.74 0)
			(effects
				(font
					(size 1.27 1.27)
				)
				(hide yes)
			)
		)
		(property "Description" ""
			(at 186.69 78.74 0)
			(effects
				(font
					(size 1.27 1.27)
				)
				(hide yes)
			)
		)
		(pin "1"
		)
		(instances
			(project "OCuLink to 10GbE adapter"
				(path ""
					(reference "#PWR0156")
					(unit 1)
				)
			)
		)
	)
	(symbol
		(lib_id "antmicroFixedInductors:L_4u7_1.55A_Bourns-SRP2512A")
		(at 44.45 226.06 0)
		(unit 1)
		(exclude_from_sim no)
		(in_bom yes)
		(on_board yes)
		(dnp no)
		(fields_autoplaced yes)
		(property "Reference" "L11"
			(at 46.99 220.98 0)
			(effects
				(font
					(size 1.27 1.27)
					(thickness 0.15)
				)
			)
		)
		(property "Value" "L_4u7_1.55A_Bourns-SRP2512A"
			(at 59.69 231.14 0)
			(effects
				(font
					(size 1.27 1.27)
					(thickness 0.15)
				)
				(justify left bottom)
				(hide yes)
			)
		)
		(property "Footprint" "antmicro-footprints:L_Bourns-SRP2512A"
			(at 59.69 233.68 0)
			(effects
				(font
					(size 1.27 1.27)
					(thickness 0.15)
				)
				(justify left bottom)
				(hide yes)
			)
		)
		(property "Datasheet" "https://www.bourns.com/docs/Product-Datasheets/srp2512a.pdf"
			(at 59.69 236.22 0)
			(effects
				(font
					(size 1.27 1.27)
					(thickness 0.15)
				)
				(justify left bottom)
				(hide yes)
			)
		)
		(property "Description" "4.7 µH Shielded Drum Core, Wirewound Inductor 1.55 A 235mOhm Max 1008 (2520 Metric)"
			(at 59.69 256.54 0)
			(effects
				(font
					(size 1.27 1.27)
				)
				(justify left bottom)
				(hide yes)
			)
		)
		(property "Val" "4u7/1.55A"
			(at 46.99 223.52 0)
			(effects
				(font
					(size 1.27 1.27)
					(thickness 0.15)
				)
			)
		)
		(property "Manufacturer" "Bourns"
			(at 59.69 238.76 0)
			(effects
				(font
					(size 1.27 1.27)
					(thickness 0.15)
				)
				(justify left bottom)
				(hide yes)
			)
		)
		(property "MPN" "SRP2512A-4R7M"
			(at 59.69 241.3 0)
			(effects
				(font
					(size 1.27 1.27)
					(thickness 0.15)
				)
				(justify left bottom)
				(hide yes)
			)
		)
		(property "ISat" "1.9 A"
			(at 59.69 243.84 0)
			(effects
				(font
					(size 1.27 1.27)
				)
				(justify left bottom)
				(hide yes)
			)
		)
		(property "IMax" "1.55 A"
			(at 59.69 246.38 0)
			(effects
				(font
					(size 1.27 1.27)
				)
				(justify left bottom)
				(hide yes)
			)
		)
		(property "Size" "2.5x2.0"
			(at 59.69 248.92 0)
			(effects
				(font
					(size 1.27 1.27)
				)
				(justify left bottom)
				(hide yes)
			)
		)
		(property "Author" "Antmicro"
			(at 59.69 251.46 0)
			(effects
				(font
					(size 1.27 1.27)
					(thickness 0.15)
				)
				(justify left bottom)
				(hide yes)
			)
		)
		(property "License" "Apache-2.0"
			(at 59.69 254 0)
			(effects
				(font
					(size 1.27 1.27)
					(thickness 0.15)
				)
				(justify left bottom)
				(hide yes)
			)
		)
		(pin "2"
		)
		(pin "1"
		)
		(instances
			(project "oculink-to-10gbe-adapter"
				(path ""
					(reference "L11")
					(unit 1)
				)
			)
		)
	)
	(symbol
		(lib_id "antmicropower:GND")
		(at 361.95 76.2 0)
		(unit 1)
		(exclude_from_sim no)
		(in_bom yes)
		(on_board yes)
		(dnp no)
		(property "Reference" "#PWR0146"
			(at 370.84 78.74 0)
			(effects
				(font
					(size 1.27 1.27)
					(thickness 0.15)
				)
				(justify left bottom)
				(hide yes)
			)
		)
		(property "Value" "GND"
			(at 361.95 80.01 0)
			(effects
				(font
					(size 1.27 1.27)
					(thickness 0.15)
				)
			)
		)
		(property "Footprint" ""
			(at 370.84 83.82 0)
			(effects
				(font
					(size 1.27 1.27)
					(thickness 0.15)
				)
				(justify left bottom)
				(hide yes)
			)
		)
		(property "Datasheet" ""
			(at 370.84 88.9 0)
			(effects
				(font
					(size 1.27 1.27)
					(thickness 0.15)
				)
				(justify left bottom)
				(hide yes)
			)
		)
		(property "Description" ""
			(at 361.95 76.2 0)
			(effects
				(font
					(size 1.27 1.27)
				)
				(hide yes)
			)
		)
		(property "Author" "Antmicro"
			(at 370.84 83.82 0)
			(effects
				(font
					(size 1.27 1.27)
					(thickness 0.15)
				)
				(justify left bottom)
				(hide yes)
			)
		)
		(property "License" "Apache-2.0"
			(at 370.84 86.36 0)
			(effects
				(font
					(size 1.27 1.27)
					(thickness 0.15)
				)
				(justify left bottom)
				(hide yes)
			)
		)
		(pin "1"
		)
		(instances
			(project "OCuLink to 10GbE adapter"
				(path ""
					(reference "#PWR0146")
					(unit 1)
				)
			)
		)
	)
	(symbol
		(lib_id "antmicropower:GND")
		(at 300.99 152.4 0)
		(unit 1)
		(exclude_from_sim no)
		(in_bom yes)
		(on_board yes)
		(dnp no)
		(property "Reference" "#PWR0209"
			(at 309.88 154.94 0)
			(effects
				(font
					(size 1.27 1.27)
					(thickness 0.15)
				)
				(justify left bottom)
				(hide yes)
			)
		)
		(property "Value" "GND"
			(at 300.99 156.21 0)
			(effects
				(font
					(size 1.27 1.27)
					(thickness 0.15)
				)
			)
		)
		(property "Footprint" ""
			(at 309.88 160.02 0)
			(effects
				(font
					(size 1.27 1.27)
					(thickness 0.15)
				)
				(justify left bottom)
				(hide yes)
			)
		)
		(property "Datasheet" ""
			(at 309.88 165.1 0)
			(effects
				(font
					(size 1.27 1.27)
					(thickness 0.15)
				)
				(justify left bottom)
				(hide yes)
			)
		)
		(property "Description" ""
			(at 300.99 152.4 0)
			(effects
				(font
					(size 1.27 1.27)
				)
				(hide yes)
			)
		)
		(property "Author" "Antmicro"
			(at 309.88 160.02 0)
			(effects
				(font
					(size 1.27 1.27)
					(thickness 0.15)
				)
				(justify left bottom)
				(hide yes)
			)
		)
		(property "License" "Apache-2.0"
			(at 309.88 162.56 0)
			(effects
				(font
					(size 1.27 1.27)
					(thickness 0.15)
				)
				(justify left bottom)
				(hide yes)
			)
		)
		(pin "1"
		)
		(instances
			(project "OCuLink to 10GbE adapter"
				(path ""
					(reference "#PWR0209")
					(unit 1)
				)
			)
		)
	)
	(symbol
		(lib_id "antmicroCapacitorsmisc:C_100u_0805")
		(at 53.34 153.67 90)
		(unit 1)
		(exclude_from_sim no)
		(in_bom yes)
		(on_board yes)
		(dnp no)
		(property "Reference" "C163"
			(at 55.118 149.86 90)
			(effects
				(font
					(size 1.27 1.27)
					(thickness 0.15)
				)
				(justify right)
			)
		)
		(property "Value" "C_100u_0805"
			(at 63.5 133.35 0)
			(effects
				(font
					(size 1.27 1.27)
					(thickness 0.15)
				)
				(justify left bottom)
				(hide yes)
			)
		)
		(property "Footprint" "antmicro-footprints:C_0805_2012Metric"
			(at 66.04 133.35 0)
			(effects
				(font
					(size 1.27 1.27)
					(thickness 0.15)
				)
				(justify left bottom)
				(hide yes)
			)
		)
		(property "Datasheet" "https://www.murata.com/products/productdetail?partno=GRM21BR60J107ME15%23"
			(at 68.58 133.35 0)
			(effects
				(font
					(size 1.27 1.27)
					(thickness 0.15)
				)
				(justify left bottom)
				(hide yes)
			)
		)
		(property "Description" "SMD Multilayer Ceramic Capacitor, 100 µF, 6.3 V, 0805 [2012 Metric], ± 20%, X5R, GRM Series"
			(at 53.34 153.67 0)
			(effects
				(font
					(size 1.27 1.27)
				)
				(hide yes)
			)
		)
		(property "MPN" "GRM21BR60J107ME15L"
			(at 71.12 133.35 0)
			(effects
				(font
					(size 1.27 1.27)
					(thickness 0.15)
				)
				(justify left bottom)
				(hide yes)
			)
		)
		(property "Manufacturer" "Murata"
			(at 73.66 133.35 0)
			(effects
				(font
					(size 1.27 1.27)
					(thickness 0.15)
				)
				(justify left bottom)
				(hide yes)
			)
		)
		(property "License" "Apache-2.0"
			(at 76.2 133.35 0)
			(effects
				(font
					(size 1.27 1.27)
					(thickness 0.15)
				)
				(justify left bottom)
				(hide yes)
			)
		)
		(property "Author" "Antmicro"
			(at 78.74 133.35 0)
			(effects
				(font
					(size 1.27 1.27)
					(thickness 0.15)
				)
				(justify left bottom)
				(hide yes)
			)
		)
		(property "Val" "100u"
			(at 55.118 152.4 90)
			(effects
				(font
					(size 1.27 1.27)
					(thickness 0.15)
				)
				(justify right)
			)
		)
		(property "Voltage" ""
			(at 81.28 133.35 0)
			(effects
				(font
					(size 1.27 1.27)
				)
				(justify left bottom)
				(hide yes)
			)
		)
		(property "Dielectric" ""
			(at 83.82 133.35 0)
			(effects
				(font
					(size 1.27 1.27)
				)
				(justify left bottom)
				(hide yes)
			)
		)
		(property "Public" "False"
			(at 86.36 133.35 0)
			(effects
				(font
					(size 1.27 1.27)
				)
				(justify left bottom)
				(hide yes)
			)
		)
		(pin "1"
		)
		(pin "2"
		)
		(instances
			(project "OCuLink to 10GbE adapter"
				(path ""
					(reference "C163")
					(unit 1)
				)
			)
		)
	)
	(symbol
		(lib_id "antmicroCapacitors0402:C_1u_25V_0402")
		(at 353.06 73.66 90)
		(unit 1)
		(exclude_from_sim no)
		(in_bom yes)
		(on_board yes)
		(dnp no)
		(property "Reference" "C111"
			(at 355.092 69.85 90)
			(effects
				(font
					(size 1.27 1.27)
					(thickness 0.15)
				)
				(justify right)
			)
		)
		(property "Value" "C_1u_25V_0402"
			(at 363.22 53.34 0)
			(effects
				(font
					(size 1.27 1.27)
					(thickness 0.15)
				)
				(justify left bottom)
				(hide yes)
			)
		)
		(property "Footprint" "antmicro-footprints:C_0402_1005Metric"
			(at 365.76 53.34 0)
			(effects
				(font
					(size 1.27 1.27)
					(thickness 0.15)
				)
				(justify left bottom)
				(hide yes)
			)
		)
		(property "Datasheet" "https://www.murata.com/products/productdetail?partno=GRM155R61E105KE11%23"
			(at 368.3 53.34 0)
			(effects
				(font
					(size 1.27 1.27)
					(thickness 0.15)
				)
				(justify left bottom)
				(hide yes)
			)
		)
		(property "Description" "SMD Multilayer Ceramic Capacitor, 1 µF, 25 V, 0402 [1005 Metric], ± 10%, X5R, GRM Series"
			(at 353.06 73.66 0)
			(effects
				(font
					(size 1.27 1.27)
				)
				(hide yes)
			)
		)
		(property "MPN" "GRM155R61E105KE11J"
			(at 370.84 53.34 0)
			(effects
				(font
					(size 1.27 1.27)
					(thickness 0.15)
				)
				(justify left bottom)
				(hide yes)
			)
		)
		(property "Manufacturer" "Murata"
			(at 373.38 53.34 0)
			(effects
				(font
					(size 1.27 1.27)
					(thickness 0.15)
				)
				(justify left bottom)
				(hide yes)
			)
		)
		(property "License" "Apache-2.0"
			(at 375.92 53.34 0)
			(effects
				(font
					(size 1.27 1.27)
					(thickness 0.15)
				)
				(justify left bottom)
				(hide yes)
			)
		)
		(property "Author" "Antmicro"
			(at 378.46 53.34 0)
			(effects
				(font
					(size 1.27 1.27)
					(thickness 0.15)
				)
				(justify left bottom)
				(hide yes)
			)
		)
		(property "Val" "1u"
			(at 355.092 72.39 90)
			(effects
				(font
					(size 1.27 1.27)
					(thickness 0.15)
				)
				(justify right)
			)
		)
		(property "Voltage" "25V"
			(at 381 53.34 0)
			(effects
				(font
					(size 1.27 1.27)
				)
				(justify left bottom)
				(hide yes)
			)
		)
		(property "Dielectric" "X5R"
			(at 383.54 53.34 0)
			(effects
				(font
					(size 1.27 1.27)
				)
				(justify left bottom)
				(hide yes)
			)
		)
		(pin "2"
		)
		(pin "1"
		)
		(instances
			(project "OCuLink to 10GbE adapter"
				(path ""
					(reference "C111")
					(unit 1)
				)
			)
		)
	)
	(symbol
		(lib_id "antmicroCapacitors0603:C_22u_16V_0603")
		(at 53.34 52.07 90)
		(unit 1)
		(exclude_from_sim no)
		(in_bom yes)
		(on_board yes)
		(dnp no)
		(property "Reference" "C80"
			(at 55.372 48.26 90)
			(effects
				(font
					(size 1.27 1.27)
					(thickness 0.15)
				)
				(justify right)
			)
		)
		(property "Value" "C_22u_16V_0603"
			(at 63.5 31.75 0)
			(effects
				(font
					(size 1.27 1.27)
					(thickness 0.15)
				)
				(justify left bottom)
				(hide yes)
			)
		)
		(property "Footprint" "antmicro-footprints:C_0603_1608Metric_EIA"
			(at 66.04 31.75 0)
			(effects
				(font
					(size 1.27 1.27)
					(thickness 0.15)
				)
				(justify left bottom)
				(hide yes)
			)
		)
		(property "Datasheet" "https://product.samsungsem.com/mlcc/CL10A226MO7JZN.do"
			(at 68.58 31.75 0)
			(effects
				(font
					(size 1.27 1.27)
					(thickness 0.15)
				)
				(justify left bottom)
				(hide yes)
			)
		)
		(property "Description" "SMD Multilayer Ceramic Capacitor"
			(at 53.34 52.07 0)
			(effects
				(font
					(size 1.27 1.27)
				)
				(hide yes)
			)
		)
		(property "MPN" "CL10A226MO7JZNC"
			(at 71.12 31.75 0)
			(effects
				(font
					(size 1.27 1.27)
					(thickness 0.15)
				)
				(justify left bottom)
				(hide yes)
			)
		)
		(property "Manufacturer" "Samsung Electro-Mechanics"
			(at 73.66 31.75 0)
			(effects
				(font
					(size 1.27 1.27)
					(thickness 0.15)
				)
				(justify left bottom)
				(hide yes)
			)
		)
		(property "License" "Apache-2.0"
			(at 76.2 31.75 0)
			(effects
				(font
					(size 1.27 1.27)
					(thickness 0.15)
				)
				(justify left bottom)
				(hide yes)
			)
		)
		(property "Author" "Antmicro"
			(at 78.74 31.75 0)
			(effects
				(font
					(size 1.27 1.27)
					(thickness 0.15)
				)
				(justify left bottom)
				(hide yes)
			)
		)
		(property "Val" "22u"
			(at 55.372 50.8 90)
			(effects
				(font
					(size 1.27 1.27)
					(thickness 0.15)
				)
				(justify right)
			)
		)
		(property "Voltage" "16V"
			(at 81.28 31.75 0)
			(effects
				(font
					(size 1.27 1.27)
				)
				(justify left bottom)
				(hide yes)
			)
		)
		(property "Dielectric" ""
			(at 83.82 31.75 0)
			(effects
				(font
					(size 1.27 1.27)
				)
				(justify left bottom)
				(hide yes)
			)
		)
		(pin "1"
		)
		(pin "2"
		)
		(instances
			(project "OCuLink to 10GbE adapter"
				(path ""
					(reference "C80")
					(unit 1)
				)
			)
		)
	)
	(symbol
		(lib_id "antmicropower:PWR_FLAG")
		(at 66.04 224.79 0)
		(unit 1)
		(exclude_from_sim no)
		(in_bom yes)
		(on_board yes)
		(dnp no)
		(fields_autoplaced yes)
		(property "Reference" "#FLG018"
			(at 66.04 222.885 0)
			(effects
				(font
					(size 1.27 1.27)
				)
				(hide yes)
			)
		)
		(property "Value" "PWR_FLAG"
			(at 66.04 219.71 0)
			(effects
				(font
					(size 1.27 1.27)
				)
			)
		)
		(property "Footprint" ""
			(at 66.04 224.79 0)
			(effects
				(font
					(size 1.27 1.27)
				)
				(hide yes)
			)
		)
		(property "Datasheet" ""
			(at 66.04 224.79 0)
			(effects
				(font
					(size 1.27 1.27)
				)
				(hide yes)
			)
		)
		(property "Description" ""
			(at 66.04 227.33 0)
			(effects
				(font
					(size 1.27 1.27)
				)
				(justify left bottom)
				(hide yes)
			)
		)
		(pin "1"
		)
		(instances
			(project "OCuLink to 10GbE adapter"
				(path ""
					(reference "#FLG018")
					(unit 1)
				)
			)
		)
	)
	(symbol
		(lib_id "antmicroCapacitors0402:C_1u_25V_0402")
		(at 370.84 113.03 90)
		(unit 1)
		(exclude_from_sim no)
		(in_bom yes)
		(on_board yes)
		(dnp no)
		(property "Reference" "C137"
			(at 372.872 109.22 90)
			(effects
				(font
					(size 1.27 1.27)
					(thickness 0.15)
				)
				(justify right)
			)
		)
		(property "Value" "C_1u_25V_0402"
			(at 381 92.71 0)
			(effects
				(font
					(size 1.27 1.27)
					(thickness 0.15)
				)
				(justify left bottom)
				(hide yes)
			)
		)
		(property "Footprint" "antmicro-footprints:C_0402_1005Metric"
			(at 383.54 92.71 0)
			(effects
				(font
					(size 1.27 1.27)
					(thickness 0.15)
				)
				(justify left bottom)
				(hide yes)
			)
		)
		(property "Datasheet" "https://www.murata.com/products/productdetail?partno=GRM155R61E105KE11%23"
			(at 386.08 92.71 0)
			(effects
				(font
					(size 1.27 1.27)
					(thickness 0.15)
				)
				(justify left bottom)
				(hide yes)
			)
		)
		(property "Description" "SMD Multilayer Ceramic Capacitor, 1 µF, 25 V, 0402 [1005 Metric], ± 10%, X5R, GRM Series"
			(at 370.84 113.03 0)
			(effects
				(font
					(size 1.27 1.27)
				)
				(hide yes)
			)
		)
		(property "MPN" "GRM155R61E105KE11J"
			(at 388.62 92.71 0)
			(effects
				(font
					(size 1.27 1.27)
					(thickness 0.15)
				)
				(justify left bottom)
				(hide yes)
			)
		)
		(property "Manufacturer" "Murata"
			(at 391.16 92.71 0)
			(effects
				(font
					(size 1.27 1.27)
					(thickness 0.15)
				)
				(justify left bottom)
				(hide yes)
			)
		)
		(property "License" "Apache-2.0"
			(at 393.7 92.71 0)
			(effects
				(font
					(size 1.27 1.27)
					(thickness 0.15)
				)
				(justify left bottom)
				(hide yes)
			)
		)
		(property "Author" "Antmicro"
			(at 396.24 92.71 0)
			(effects
				(font
					(size 1.27 1.27)
					(thickness 0.15)
				)
				(justify left bottom)
				(hide yes)
			)
		)
		(property "Val" "1u"
			(at 372.872 111.76 90)
			(effects
				(font
					(size 1.27 1.27)
					(thickness 0.15)
				)
				(justify right)
			)
		)
		(property "Voltage" "25V"
			(at 398.78 92.71 0)
			(effects
				(font
					(size 1.27 1.27)
				)
				(justify left bottom)
				(hide yes)
			)
		)
		(property "Dielectric" "X5R"
			(at 401.32 92.71 0)
			(effects
				(font
					(size 1.27 1.27)
				)
				(justify left bottom)
				(hide yes)
			)
		)
		(pin "2"
		)
		(pin "1"
		)
		(instances
			(project "OCuLink to 10GbE adapter"
				(path ""
					(reference "C137")
					(unit 1)
				)
			)
		)
	)
	(symbol
		(lib_id "antmicropower:GND")
		(at 397.51 54.61 0)
		(unit 1)
		(exclude_from_sim no)
		(in_bom yes)
		(on_board yes)
		(dnp no)
		(property "Reference" "#PWR0132"
			(at 406.4 57.15 0)
			(effects
				(font
					(size 1.27 1.27)
					(thickness 0.15)
				)
				(justify left bottom)
				(hide yes)
			)
		)
		(property "Value" "GND"
			(at 397.51 58.42 0)
			(effects
				(font
					(size 1.27 1.27)
					(thickness 0.15)
				)
			)
		)
		(property "Footprint" ""
			(at 406.4 62.23 0)
			(effects
				(font
					(size 1.27 1.27)
					(thickness 0.15)
				)
				(justify left bottom)
				(hide yes)
			)
		)
		(property "Datasheet" ""
			(at 406.4 67.31 0)
			(effects
				(font
					(size 1.27 1.27)
					(thickness 0.15)
				)
				(justify left bottom)
				(hide yes)
			)
		)
		(property "Description" ""
			(at 397.51 54.61 0)
			(effects
				(font
					(size 1.27 1.27)
				)
				(hide yes)
			)
		)
		(property "Author" "Antmicro"
			(at 406.4 62.23 0)
			(effects
				(font
					(size 1.27 1.27)
					(thickness 0.15)
				)
				(justify left bottom)
				(hide yes)
			)
		)
		(property "License" "Apache-2.0"
			(at 406.4 64.77 0)
			(effects
				(font
					(size 1.27 1.27)
					(thickness 0.15)
				)
				(justify left bottom)
				(hide yes)
			)
		)
		(pin "1"
		)
		(instances
			(project "OCuLink to 10GbE adapter"
				(path ""
					(reference "#PWR0132")
					(unit 1)
				)
			)
		)
	)
	(symbol
		(lib_id "antmicropower:VDD")
		(at 156.21 78.74 0)
		(unit 1)
		(exclude_from_sim no)
		(in_bom yes)
		(on_board yes)
		(dnp no)
		(property "Reference" "#PWR0153"
			(at 156.21 82.55 0)
			(effects
				(font
					(size 1.27 1.27)
				)
				(hide yes)
			)
		)
		(property "Value" "XFI_VDD"
			(at 156.21 74.93 0)
			(effects
				(font
					(size 1.27 1.27)
				)
			)
		)
		(property "Footprint" ""
			(at 156.21 78.74 0)
			(effects
				(font
					(size 1.27 1.27)
				)
				(hide yes)
			)
		)
		(property "Datasheet" ""
			(at 156.21 78.74 0)
			(effects
				(font
					(size 1.27 1.27)
				)
				(hide yes)
			)
		)
		(property "Description" ""
			(at 156.21 78.74 0)
			(effects
				(font
					(size 1.27 1.27)
				)
				(hide yes)
			)
		)
		(pin "1"
		)
		(instances
			(project "OCuLink to 10GbE adapter"
				(path ""
					(reference "#PWR0153")
					(unit 1)
				)
			)
		)
	)
	(symbol
		(lib_id "antmicroCapacitors0603:C_22u_16V_0603")
		(at 370.84 130.81 90)
		(unit 1)
		(exclude_from_sim no)
		(in_bom yes)
		(on_board yes)
		(dnp no)
		(fields_autoplaced yes)
		(property "Reference" "C153"
			(at 373.38 126.9936 90)
			(effects
				(font
					(size 1.27 1.27)
					(thickness 0.15)
				)
				(justify right)
			)
		)
		(property "Value" "C_22u_16V_0603"
			(at 381 110.49 0)
			(effects
				(font
					(size 1.27 1.27)
					(thickness 0.15)
				)
				(justify left bottom)
				(hide yes)
			)
		)
		(property "Footprint" "antmicro-footprints:C_0603_1608Metric_EIA"
			(at 383.54 110.49 0)
			(effects
				(font
					(size 1.27 1.27)
					(thickness 0.15)
				)
				(justify left bottom)
				(hide yes)
			)
		)
		(property "Datasheet" "https://product.samsungsem.com/mlcc/CL10A226MO7JZN.do"
			(at 386.08 110.49 0)
			(effects
				(font
					(size 1.27 1.27)
					(thickness 0.15)
				)
				(justify left bottom)
				(hide yes)
			)
		)
		(property "Description" "SMD Multilayer Ceramic Capacitor"
			(at 370.84 130.81 0)
			(effects
				(font
					(size 1.27 1.27)
				)
				(hide yes)
			)
		)
		(property "MPN" "CL10A226MO7JZNC"
			(at 388.62 110.49 0)
			(effects
				(font
					(size 1.27 1.27)
					(thickness 0.15)
				)
				(justify left bottom)
				(hide yes)
			)
		)
		(property "Manufacturer" "Samsung Electro-Mechanics"
			(at 391.16 110.49 0)
			(effects
				(font
					(size 1.27 1.27)
					(thickness 0.15)
				)
				(justify left bottom)
				(hide yes)
			)
		)
		(property "License" "Apache-2.0"
			(at 393.7 110.49 0)
			(effects
				(font
					(size 1.27 1.27)
					(thickness 0.15)
				)
				(justify left bottom)
				(hide yes)
			)
		)
		(property "Author" "Antmicro"
			(at 396.24 110.49 0)
			(effects
				(font
					(size 1.27 1.27)
					(thickness 0.15)
				)
				(justify left bottom)
				(hide yes)
			)
		)
		(property "Val" "22u"
			(at 373.38 129.5336 90)
			(effects
				(font
					(size 1.27 1.27)
					(thickness 0.15)
				)
				(justify right)
			)
		)
		(property "Voltage" "16V"
			(at 398.78 110.49 0)
			(effects
				(font
					(size 1.27 1.27)
				)
				(justify left bottom)
				(hide yes)
			)
		)
		(property "Dielectric" ""
			(at 401.32 110.49 0)
			(effects
				(font
					(size 1.27 1.27)
				)
				(justify left bottom)
				(hide yes)
			)
		)
		(pin "1"
		)
		(pin "2"
		)
		(instances
			(project "OCuLink to 10GbE adapter"
				(path ""
					(reference "C153")
					(unit 1)
				)
			)
		)
	)
	(symbol
		(lib_id "antmicropower:GND")
		(at 53.34 102.87 0)
		(unit 1)
		(exclude_from_sim no)
		(in_bom yes)
		(on_board yes)
		(dnp no)
		(property "Reference" "#PWR0176"
			(at 62.23 105.41 0)
			(effects
				(font
					(size 1.27 1.27)
					(thickness 0.15)
				)
				(justify left bottom)
				(hide yes)
			)
		)
		(property "Value" "GND"
			(at 53.34 106.68 0)
			(effects
				(font
					(size 1.27 1.27)
					(thickness 0.15)
				)
			)
		)
		(property "Footprint" ""
			(at 62.23 110.49 0)
			(effects
				(font
					(size 1.27 1.27)
					(thickness 0.15)
				)
				(justify left bottom)
				(hide yes)
			)
		)
		(property "Datasheet" ""
			(at 62.23 115.57 0)
			(effects
				(font
					(size 1.27 1.27)
					(thickness 0.15)
				)
				(justify left bottom)
				(hide yes)
			)
		)
		(property "Description" ""
			(at 53.34 102.87 0)
			(effects
				(font
					(size 1.27 1.27)
				)
				(hide yes)
			)
		)
		(property "Author" "Antmicro"
			(at 62.23 110.49 0)
			(effects
				(font
					(size 1.27 1.27)
					(thickness 0.15)
				)
				(justify left bottom)
				(hide yes)
			)
		)
		(property "License" "Apache-2.0"
			(at 62.23 113.03 0)
			(effects
				(font
					(size 1.27 1.27)
					(thickness 0.15)
				)
				(justify left bottom)
				(hide yes)
			)
		)
		(pin "1"
		)
		(instances
			(project "OCuLink to 10GbE adapter"
				(path ""
					(reference "#PWR0176")
					(unit 1)
				)
			)
		)
	)
	(symbol
		(lib_id "antmicropower:GND")
		(at 335.28 76.2 0)
		(unit 1)
		(exclude_from_sim no)
		(in_bom yes)
		(on_board yes)
		(dnp no)
		(property "Reference" "#PWR0143"
			(at 344.17 78.74 0)
			(effects
				(font
					(size 1.27 1.27)
					(thickness 0.15)
				)
				(justify left bottom)
				(hide yes)
			)
		)
		(property "Value" "GND"
			(at 335.28 80.01 0)
			(effects
				(font
					(size 1.27 1.27)
					(thickness 0.15)
				)
			)
		)
		(property "Footprint" ""
			(at 344.17 83.82 0)
			(effects
				(font
					(size 1.27 1.27)
					(thickness 0.15)
				)
				(justify left bottom)
				(hide yes)
			)
		)
		(property "Datasheet" ""
			(at 344.17 88.9 0)
			(effects
				(font
					(size 1.27 1.27)
					(thickness 0.15)
				)
				(justify left bottom)
				(hide yes)
			)
		)
		(property "Description" ""
			(at 335.28 76.2 0)
			(effects
				(font
					(size 1.27 1.27)
				)
				(hide yes)
			)
		)
		(property "Author" "Antmicro"
			(at 344.17 83.82 0)
			(effects
				(font
					(size 1.27 1.27)
					(thickness 0.15)
				)
				(justify left bottom)
				(hide yes)
			)
		)
		(property "License" "Apache-2.0"
			(at 344.17 86.36 0)
			(effects
				(font
					(size 1.27 1.27)
					(thickness 0.15)
				)
				(justify left bottom)
				(hide yes)
			)
		)
		(pin "1"
		)
		(instances
			(project "OCuLink to 10GbE adapter"
				(path ""
					(reference "#PWR0143")
					(unit 1)
				)
			)
		)
	)
	(symbol
		(lib_id "antmicroCapacitors0402:C_1u_25V_0402")
		(at 335.28 73.66 90)
		(unit 1)
		(exclude_from_sim no)
		(in_bom yes)
		(on_board yes)
		(dnp no)
		(property "Reference" "C109"
			(at 337.312 69.85 90)
			(effects
				(font
					(size 1.27 1.27)
					(thickness 0.15)
				)
				(justify right)
			)
		)
		(property "Value" "C_1u_25V_0402"
			(at 345.44 53.34 0)
			(effects
				(font
					(size 1.27 1.27)
					(thickness 0.15)
				)
				(justify left bottom)
				(hide yes)
			)
		)
		(property "Footprint" "antmicro-footprints:C_0402_1005Metric"
			(at 347.98 53.34 0)
			(effects
				(font
					(size 1.27 1.27)
					(thickness 0.15)
				)
				(justify left bottom)
				(hide yes)
			)
		)
		(property "Datasheet" "https://www.murata.com/products/productdetail?partno=GRM155R61E105KE11%23"
			(at 350.52 53.34 0)
			(effects
				(font
					(size 1.27 1.27)
					(thickness 0.15)
				)
				(justify left bottom)
				(hide yes)
			)
		)
		(property "Description" "SMD Multilayer Ceramic Capacitor, 1 µF, 25 V, 0402 [1005 Metric], ± 10%, X5R, GRM Series"
			(at 335.28 73.66 0)
			(effects
				(font
					(size 1.27 1.27)
				)
				(hide yes)
			)
		)
		(property "MPN" "GRM155R61E105KE11J"
			(at 353.06 53.34 0)
			(effects
				(font
					(size 1.27 1.27)
					(thickness 0.15)
				)
				(justify left bottom)
				(hide yes)
			)
		)
		(property "Manufacturer" "Murata"
			(at 355.6 53.34 0)
			(effects
				(font
					(size 1.27 1.27)
					(thickness 0.15)
				)
				(justify left bottom)
				(hide yes)
			)
		)
		(property "License" "Apache-2.0"
			(at 358.14 53.34 0)
			(effects
				(font
					(size 1.27 1.27)
					(thickness 0.15)
				)
				(justify left bottom)
				(hide yes)
			)
		)
		(property "Author" "Antmicro"
			(at 360.68 53.34 0)
			(effects
				(font
					(size 1.27 1.27)
					(thickness 0.15)
				)
				(justify left bottom)
				(hide yes)
			)
		)
		(property "Val" "1u"
			(at 337.312 72.39 90)
			(effects
				(font
					(size 1.27 1.27)
					(thickness 0.15)
				)
				(justify right)
			)
		)
		(property "Voltage" "25V"
			(at 363.22 53.34 0)
			(effects
				(font
					(size 1.27 1.27)
				)
				(justify left bottom)
				(hide yes)
			)
		)
		(property "Dielectric" "X5R"
			(at 365.76 53.34 0)
			(effects
				(font
					(size 1.27 1.27)
				)
				(justify left bottom)
				(hide yes)
			)
		)
		(pin "2"
		)
		(pin "1"
		)
		(instances
			(project "OCuLink to 10GbE adapter"
				(path ""
					(reference "C109")
					(unit 1)
				)
			)
		)
	)
	(symbol
		(lib_id "antmicroCapacitors0402:C_1u_25V_0402")
		(at 80.01 127 90)
		(unit 1)
		(exclude_from_sim no)
		(in_bom yes)
		(on_board yes)
		(dnp no)
		(property "Reference" "C141"
			(at 81.788 123.19 90)
			(effects
				(font
					(size 1.27 1.27)
					(thickness 0.15)
				)
				(justify right)
			)
		)
		(property "Value" "C_1u_25V_0402"
			(at 90.17 106.68 0)
			(effects
				(font
					(size 1.27 1.27)
					(thickness 0.15)
				)
				(justify left bottom)
				(hide yes)
			)
		)
		(property "Footprint" "antmicro-footprints:C_0402_1005Metric"
			(at 92.71 106.68 0)
			(effects
				(font
					(size 1.27 1.27)
					(thickness 0.15)
				)
				(justify left bottom)
				(hide yes)
			)
		)
		(property "Datasheet" "https://www.murata.com/products/productdetail?partno=GRM155R61E105KE11%23"
			(at 95.25 106.68 0)
			(effects
				(font
					(size 1.27 1.27)
					(thickness 0.15)
				)
				(justify left bottom)
				(hide yes)
			)
		)
		(property "Description" "SMD Multilayer Ceramic Capacitor, 1 µF, 25 V, 0402 [1005 Metric], ± 10%, X5R, GRM Series"
			(at 80.01 127 0)
			(effects
				(font
					(size 1.27 1.27)
				)
				(hide yes)
			)
		)
		(property "MPN" "GRM155R61E105KE11J"
			(at 97.79 106.68 0)
			(effects
				(font
					(size 1.27 1.27)
					(thickness 0.15)
				)
				(justify left bottom)
				(hide yes)
			)
		)
		(property "Manufacturer" "Murata"
			(at 100.33 106.68 0)
			(effects
				(font
					(size 1.27 1.27)
					(thickness 0.15)
				)
				(justify left bottom)
				(hide yes)
			)
		)
		(property "License" "Apache-2.0"
			(at 102.87 106.68 0)
			(effects
				(font
					(size 1.27 1.27)
					(thickness 0.15)
				)
				(justify left bottom)
				(hide yes)
			)
		)
		(property "Author" "Antmicro"
			(at 105.41 106.68 0)
			(effects
				(font
					(size 1.27 1.27)
					(thickness 0.15)
				)
				(justify left bottom)
				(hide yes)
			)
		)
		(property "Val" "1u"
			(at 81.788 125.73 90)
			(effects
				(font
					(size 1.27 1.27)
					(thickness 0.15)
				)
				(justify right)
			)
		)
		(property "Voltage" "25V"
			(at 107.95 106.68 0)
			(effects
				(font
					(size 1.27 1.27)
				)
				(justify left bottom)
				(hide yes)
			)
		)
		(property "Dielectric" "X5R"
			(at 110.49 106.68 0)
			(effects
				(font
					(size 1.27 1.27)
				)
				(justify left bottom)
				(hide yes)
			)
		)
		(pin "2"
		)
		(pin "1"
		)
		(instances
			(project "OCuLink to 10GbE adapter"
				(path ""
					(reference "C141")
					(unit 1)
				)
			)
		)
	)
	(symbol
		(lib_id "antmicroCapacitors0402:C_1u_25V_0402")
		(at 88.9 180.34 90)
		(unit 1)
		(exclude_from_sim no)
		(in_bom yes)
		(on_board yes)
		(dnp no)
		(property "Reference" "C175"
			(at 90.932 176.53 90)
			(effects
				(font
					(size 1.27 1.27)
					(thickness 0.15)
				)
				(justify right)
			)
		)
		(property "Value" "C_1u_25V_0402"
			(at 99.06 160.02 0)
			(effects
				(font
					(size 1.27 1.27)
					(thickness 0.15)
				)
				(justify left bottom)
				(hide yes)
			)
		)
		(property "Footprint" "antmicro-footprints:C_0402_1005Metric"
			(at 101.6 160.02 0)
			(effects
				(font
					(size 1.27 1.27)
					(thickness 0.15)
				)
				(justify left bottom)
				(hide yes)
			)
		)
		(property "Datasheet" "https://www.murata.com/products/productdetail?partno=GRM155R61E105KE11%23"
			(at 104.14 160.02 0)
			(effects
				(font
					(size 1.27 1.27)
					(thickness 0.15)
				)
				(justify left bottom)
				(hide yes)
			)
		)
		(property "Description" "SMD Multilayer Ceramic Capacitor, 1 µF, 25 V, 0402 [1005 Metric], ± 10%, X5R, GRM Series"
			(at 88.9 180.34 0)
			(effects
				(font
					(size 1.27 1.27)
				)
				(hide yes)
			)
		)
		(property "MPN" "GRM155R61E105KE11J"
			(at 106.68 160.02 0)
			(effects
				(font
					(size 1.27 1.27)
					(thickness 0.15)
				)
				(justify left bottom)
				(hide yes)
			)
		)
		(property "Manufacturer" "Murata"
			(at 109.22 160.02 0)
			(effects
				(font
					(size 1.27 1.27)
					(thickness 0.15)
				)
				(justify left bottom)
				(hide yes)
			)
		)
		(property "License" "Apache-2.0"
			(at 111.76 160.02 0)
			(effects
				(font
					(size 1.27 1.27)
					(thickness 0.15)
				)
				(justify left bottom)
				(hide yes)
			)
		)
		(property "Author" "Antmicro"
			(at 114.3 160.02 0)
			(effects
				(font
					(size 1.27 1.27)
					(thickness 0.15)
				)
				(justify left bottom)
				(hide yes)
			)
		)
		(property "Val" "1u"
			(at 90.932 179.07 90)
			(effects
				(font
					(size 1.27 1.27)
					(thickness 0.15)
				)
				(justify right)
			)
		)
		(property "Voltage" "25V"
			(at 116.84 160.02 0)
			(effects
				(font
					(size 1.27 1.27)
				)
				(justify left bottom)
				(hide yes)
			)
		)
		(property "Dielectric" "X5R"
			(at 119.38 160.02 0)
			(effects
				(font
					(size 1.27 1.27)
				)
				(justify left bottom)
				(hide yes)
			)
		)
		(pin "2"
		)
		(pin "1"
		)
		(instances
			(project "OCuLink to 10GbE adapter"
				(path ""
					(reference "C175")
					(unit 1)
				)
			)
		)
	)
	(symbol
		(lib_id "antmicroCapacitorsmisc:C_100u_0805")
		(at 53.34 180.34 90)
		(unit 1)
		(exclude_from_sim no)
		(in_bom yes)
		(on_board yes)
		(dnp no)
		(property "Reference" "C172"
			(at 55.118 176.53 90)
			(effects
				(font
					(size 1.27 1.27)
					(thickness 0.15)
				)
				(justify right)
			)
		)
		(property "Value" "C_100u_0805"
			(at 63.5 160.02 0)
			(effects
				(font
					(size 1.27 1.27)
					(thickness 0.15)
				)
				(justify left bottom)
				(hide yes)
			)
		)
		(property "Footprint" "antmicro-footprints:C_0805_2012Metric"
			(at 66.04 160.02 0)
			(effects
				(font
					(size 1.27 1.27)
					(thickness 0.15)
				)
				(justify left bottom)
				(hide yes)
			)
		)
		(property "Datasheet" "https://www.murata.com/products/productdetail?partno=GRM21BR60J107ME15%23"
			(at 68.58 160.02 0)
			(effects
				(font
					(size 1.27 1.27)
					(thickness 0.15)
				)
				(justify left bottom)
				(hide yes)
			)
		)
		(property "Description" "SMD Multilayer Ceramic Capacitor, 100 µF, 6.3 V, 0805 [2012 Metric], ± 20%, X5R, GRM Series"
			(at 53.34 180.34 0)
			(effects
				(font
					(size 1.27 1.27)
				)
				(hide yes)
			)
		)
		(property "MPN" "GRM21BR60J107ME15L"
			(at 71.12 160.02 0)
			(effects
				(font
					(size 1.27 1.27)
					(thickness 0.15)
				)
				(justify left bottom)
				(hide yes)
			)
		)
		(property "Manufacturer" "Murata"
			(at 73.66 160.02 0)
			(effects
				(font
					(size 1.27 1.27)
					(thickness 0.15)
				)
				(justify left bottom)
				(hide yes)
			)
		)
		(property "License" "Apache-2.0"
			(at 76.2 160.02 0)
			(effects
				(font
					(size 1.27 1.27)
					(thickness 0.15)
				)
				(justify left bottom)
				(hide yes)
			)
		)
		(property "Author" "Antmicro"
			(at 78.74 160.02 0)
			(effects
				(font
					(size 1.27 1.27)
					(thickness 0.15)
				)
				(justify left bottom)
				(hide yes)
			)
		)
		(property "Val" "100u"
			(at 55.118 179.07 90)
			(effects
				(font
					(size 1.27 1.27)
					(thickness 0.15)
				)
				(justify right)
			)
		)
		(property "Voltage" ""
			(at 81.28 160.02 0)
			(effects
				(font
					(size 1.27 1.27)
				)
				(justify left bottom)
				(hide yes)
			)
		)
		(property "Dielectric" ""
			(at 83.82 160.02 0)
			(effects
				(font
					(size 1.27 1.27)
				)
				(justify left bottom)
				(hide yes)
			)
		)
		(property "Public" "False"
			(at 86.36 160.02 0)
			(effects
				(font
					(size 1.27 1.27)
				)
				(justify left bottom)
				(hide yes)
			)
		)
		(pin "1"
		)
		(pin "2"
		)
		(instances
			(project "OCuLink to 10GbE adapter"
				(path ""
					(reference "C172")
					(unit 1)
				)
			)
		)
	)
	(symbol
		(lib_id "antmicroCapacitors0402:C_1u_25V_0402")
		(at 388.62 73.66 90)
		(unit 1)
		(exclude_from_sim no)
		(in_bom yes)
		(on_board yes)
		(dnp no)
		(property "Reference" "C115"
			(at 390.652 69.85 90)
			(effects
				(font
					(size 1.27 1.27)
					(thickness 0.15)
				)
				(justify right)
			)
		)
		(property "Value" "C_1u_25V_0402"
			(at 398.78 53.34 0)
			(effects
				(font
					(size 1.27 1.27)
					(thickness 0.15)
				)
				(justify left bottom)
				(hide yes)
			)
		)
		(property "Footprint" "antmicro-footprints:C_0402_1005Metric"
			(at 401.32 53.34 0)
			(effects
				(font
					(size 1.27 1.27)
					(thickness 0.15)
				)
				(justify left bottom)
				(hide yes)
			)
		)
		(property "Datasheet" "https://www.murata.com/products/productdetail?partno=GRM155R61E105KE11%23"
			(at 403.86 53.34 0)
			(effects
				(font
					(size 1.27 1.27)
					(thickness 0.15)
				)
				(justify left bottom)
				(hide yes)
			)
		)
		(property "Description" "SMD Multilayer Ceramic Capacitor, 1 µF, 25 V, 0402 [1005 Metric], ± 10%, X5R, GRM Series"
			(at 388.62 73.66 0)
			(effects
				(font
					(size 1.27 1.27)
				)
				(hide yes)
			)
		)
		(property "MPN" "GRM155R61E105KE11J"
			(at 406.4 53.34 0)
			(effects
				(font
					(size 1.27 1.27)
					(thickness 0.15)
				)
				(justify left bottom)
				(hide yes)
			)
		)
		(property "Manufacturer" "Murata"
			(at 408.94 53.34 0)
			(effects
				(font
					(size 1.27 1.27)
					(thickness 0.15)
				)
				(justify left bottom)
				(hide yes)
			)
		)
		(property "License" "Apache-2.0"
			(at 411.48 53.34 0)
			(effects
				(font
					(size 1.27 1.27)
					(thickness 0.15)
				)
				(justify left bottom)
				(hide yes)
			)
		)
		(property "Author" "Antmicro"
			(at 414.02 53.34 0)
			(effects
				(font
					(size 1.27 1.27)
					(thickness 0.15)
				)
				(justify left bottom)
				(hide yes)
			)
		)
		(property "Val" "1u"
			(at 390.652 72.39 90)
			(effects
				(font
					(size 1.27 1.27)
					(thickness 0.15)
				)
				(justify right)
			)
		)
		(property "Voltage" "25V"
			(at 416.56 53.34 0)
			(effects
				(font
					(size 1.27 1.27)
				)
				(justify left bottom)
				(hide yes)
			)
		)
		(property "Dielectric" "X5R"
			(at 419.1 53.34 0)
			(effects
				(font
					(size 1.27 1.27)
				)
				(justify left bottom)
				(hide yes)
			)
		)
		(pin "2"
		)
		(pin "1"
		)
		(instances
			(project "OCuLink to 10GbE adapter"
				(path ""
					(reference "C115")
					(unit 1)
				)
			)
		)
	)
	(symbol
		(lib_id "antmicropower:GND")
		(at 379.73 76.2 0)
		(unit 1)
		(exclude_from_sim no)
		(in_bom yes)
		(on_board yes)
		(dnp no)
		(property "Reference" "#PWR0148"
			(at 388.62 78.74 0)
			(effects
				(font
					(size 1.27 1.27)
					(thickness 0.15)
				)
				(justify left bottom)
				(hide yes)
			)
		)
		(property "Value" "GND"
			(at 379.73 80.01 0)
			(effects
				(font
					(size 1.27 1.27)
					(thickness 0.15)
				)
			)
		)
		(property "Footprint" ""
			(at 388.62 83.82 0)
			(effects
				(font
					(size 1.27 1.27)
					(thickness 0.15)
				)
				(justify left bottom)
				(hide yes)
			)
		)
		(property "Datasheet" ""
			(at 388.62 88.9 0)
			(effects
				(font
					(size 1.27 1.27)
					(thickness 0.15)
				)
				(justify left bottom)
				(hide yes)
			)
		)
		(property "Description" ""
			(at 379.73 76.2 0)
			(effects
				(font
					(size 1.27 1.27)
				)
				(hide yes)
			)
		)
		(property "Author" "Antmicro"
			(at 388.62 83.82 0)
			(effects
				(font
					(size 1.27 1.27)
					(thickness 0.15)
				)
				(justify left bottom)
				(hide yes)
			)
		)
		(property "License" "Apache-2.0"
			(at 388.62 86.36 0)
			(effects
				(font
					(size 1.27 1.27)
					(thickness 0.15)
				)
				(justify left bottom)
				(hide yes)
			)
		)
		(pin "1"
		)
		(instances
			(project "OCuLink to 10GbE adapter"
				(path ""
					(reference "#PWR0148")
					(unit 1)
				)
			)
		)
	)
	(symbol
		(lib_id "antmicropower:GND")
		(at 97.79 76.2 0)
		(unit 1)
		(exclude_from_sim no)
		(in_bom yes)
		(on_board yes)
		(dnp no)
		(property "Reference" "#PWR0136"
			(at 106.68 78.74 0)
			(effects
				(font
					(size 1.27 1.27)
					(thickness 0.15)
				)
				(justify left bottom)
				(hide yes)
			)
		)
		(property "Value" "GND"
			(at 97.79 80.01 0)
			(effects
				(font
					(size 1.27 1.27)
					(thickness 0.15)
				)
			)
		)
		(property "Footprint" ""
			(at 106.68 83.82 0)
			(effects
				(font
					(size 1.27 1.27)
					(thickness 0.15)
				)
				(justify left bottom)
				(hide yes)
			)
		)
		(property "Datasheet" ""
			(at 106.68 88.9 0)
			(effects
				(font
					(size 1.27 1.27)
					(thickness 0.15)
				)
				(justify left bottom)
				(hide yes)
			)
		)
		(property "Description" ""
			(at 97.79 76.2 0)
			(effects
				(font
					(size 1.27 1.27)
				)
				(hide yes)
			)
		)
		(property "Author" "Antmicro"
			(at 106.68 83.82 0)
			(effects
				(font
					(size 1.27 1.27)
					(thickness 0.15)
				)
				(justify left bottom)
				(hide yes)
			)
		)
		(property "License" "Apache-2.0"
			(at 106.68 86.36 0)
			(effects
				(font
					(size 1.27 1.27)
					(thickness 0.15)
				)
				(justify left bottom)
				(hide yes)
			)
		)
		(pin "1"
		)
		(instances
			(project "OCuLink to 10GbE adapter"
				(path ""
					(reference "#PWR0136")
					(unit 1)
				)
			)
		)
	)
	(symbol
		(lib_id "antmicropower:PWR_FLAG")
		(at 289.56 139.7 0)
		(unit 1)
		(exclude_from_sim no)
		(in_bom yes)
		(on_board yes)
		(dnp no)
		(property "Reference" "#FLG014"
			(at 289.56 137.795 0)
			(effects
				(font
					(size 1.27 1.27)
				)
				(hide yes)
			)
		)
		(property "Value" "PWR_FLAG"
			(at 289.56 135.89 0)
			(effects
				(font
					(size 1.27 1.27)
				)
			)
		)
		(property "Footprint" ""
			(at 289.56 139.7 0)
			(effects
				(font
					(size 1.27 1.27)
				)
				(hide yes)
			)
		)
		(property "Datasheet" ""
			(at 289.56 139.7 0)
			(effects
				(font
					(size 1.27 1.27)
				)
				(hide yes)
			)
		)
		(property "Description" ""
			(at 289.56 139.7 0)
			(effects
				(font
					(size 1.27 1.27)
				)
				(hide yes)
			)
		)
		(pin "1"
		)
		(instances
			(project "OCuLink to 10GbE adapter"
				(path ""
					(reference "#FLG014")
					(unit 1)
				)
			)
		)
	)
	(symbol
		(lib_id "antmicropower:GND")
		(at 62.23 76.2 0)
		(unit 1)
		(exclude_from_sim no)
		(in_bom yes)
		(on_board yes)
		(dnp no)
		(property "Reference" "#PWR0134"
			(at 71.12 78.74 0)
			(effects
				(font
					(size 1.27 1.27)
					(thickness 0.15)
				)
				(justify left bottom)
				(hide yes)
			)
		)
		(property "Value" "GND"
			(at 62.23 80.01 0)
			(effects
				(font
					(size 1.27 1.27)
					(thickness 0.15)
				)
			)
		)
		(property "Footprint" ""
			(at 71.12 83.82 0)
			(effects
				(font
					(size 1.27 1.27)
					(thickness 0.15)
				)
				(justify left bottom)
				(hide yes)
			)
		)
		(property "Datasheet" ""
			(at 71.12 88.9 0)
			(effects
				(font
					(size 1.27 1.27)
					(thickness 0.15)
				)
				(justify left bottom)
				(hide yes)
			)
		)
		(property "Description" ""
			(at 62.23 76.2 0)
			(effects
				(font
					(size 1.27 1.27)
				)
				(hide yes)
			)
		)
		(property "Author" "Antmicro"
			(at 71.12 83.82 0)
			(effects
				(font
					(size 1.27 1.27)
					(thickness 0.15)
				)
				(justify left bottom)
				(hide yes)
			)
		)
		(property "License" "Apache-2.0"
			(at 71.12 86.36 0)
			(effects
				(font
					(size 1.27 1.27)
					(thickness 0.15)
				)
				(justify left bottom)
				(hide yes)
			)
		)
		(pin "1"
		)
		(instances
			(project "OCuLink to 10GbE adapter"
				(path ""
					(reference "#PWR0134")
					(unit 1)
				)
			)
		)
	)
	(symbol
		(lib_id "antmicroCapacitors0402:C_1u_25V_0402")
		(at 106.68 73.66 90)
		(unit 1)
		(exclude_from_sim no)
		(in_bom yes)
		(on_board yes)
		(dnp no)
		(property "Reference" "C103"
			(at 108.712 69.85 90)
			(effects
				(font
					(size 1.27 1.27)
					(thickness 0.15)
				)
				(justify right)
			)
		)
		(property "Value" "C_1u_25V_0402"
			(at 116.84 53.34 0)
			(effects
				(font
					(size 1.27 1.27)
					(thickness 0.15)
				)
				(justify left bottom)
				(hide yes)
			)
		)
		(property "Footprint" "antmicro-footprints:C_0402_1005Metric"
			(at 119.38 53.34 0)
			(effects
				(font
					(size 1.27 1.27)
					(thickness 0.15)
				)
				(justify left bottom)
				(hide yes)
			)
		)
		(property "Datasheet" "https://www.murata.com/products/productdetail?partno=GRM155R61E105KE11%23"
			(at 121.92 53.34 0)
			(effects
				(font
					(size 1.27 1.27)
					(thickness 0.15)
				)
				(justify left bottom)
				(hide yes)
			)
		)
		(property "Description" "SMD Multilayer Ceramic Capacitor, 1 µF, 25 V, 0402 [1005 Metric], ± 10%, X5R, GRM Series"
			(at 106.68 73.66 0)
			(effects
				(font
					(size 1.27 1.27)
				)
				(hide yes)
			)
		)
		(property "MPN" "GRM155R61E105KE11J"
			(at 124.46 53.34 0)
			(effects
				(font
					(size 1.27 1.27)
					(thickness 0.15)
				)
				(justify left bottom)
				(hide yes)
			)
		)
		(property "Manufacturer" "Murata"
			(at 127 53.34 0)
			(effects
				(font
					(size 1.27 1.27)
					(thickness 0.15)
				)
				(justify left bottom)
				(hide yes)
			)
		)
		(property "License" "Apache-2.0"
			(at 129.54 53.34 0)
			(effects
				(font
					(size 1.27 1.27)
					(thickness 0.15)
				)
				(justify left bottom)
				(hide yes)
			)
		)
		(property "Author" "Antmicro"
			(at 132.08 53.34 0)
			(effects
				(font
					(size 1.27 1.27)
					(thickness 0.15)
				)
				(justify left bottom)
				(hide yes)
			)
		)
		(property "Val" "1u"
			(at 108.712 72.39 90)
			(effects
				(font
					(size 1.27 1.27)
					(thickness 0.15)
				)
				(justify right)
			)
		)
		(property "Voltage" "25V"
			(at 134.62 53.34 0)
			(effects
				(font
					(size 1.27 1.27)
				)
				(justify left bottom)
				(hide yes)
			)
		)
		(property "Dielectric" "X5R"
			(at 137.16 53.34 0)
			(effects
				(font
					(size 1.27 1.27)
				)
				(justify left bottom)
				(hide yes)
			)
		)
		(pin "2"
		)
		(pin "1"
		)
		(instances
			(project "OCuLink to 10GbE adapter"
				(path ""
					(reference "C103")
					(unit 1)
				)
			)
		)
	)
	(symbol
		(lib_id "antmicropower:GND")
		(at 388.62 93.98 0)
		(unit 1)
		(exclude_from_sim no)
		(in_bom yes)
		(on_board yes)
		(dnp no)
		(property "Reference" "#PWR0173"
			(at 397.51 96.52 0)
			(effects
				(font
					(size 1.27 1.27)
					(thickness 0.15)
				)
				(justify left bottom)
				(hide yes)
			)
		)
		(property "Value" "GND"
			(at 388.62 97.79 0)
			(effects
				(font
					(size 1.27 1.27)
					(thickness 0.15)
				)
			)
		)
		(property "Footprint" ""
			(at 397.51 101.6 0)
			(effects
				(font
					(size 1.27 1.27)
					(thickness 0.15)
				)
				(justify left bottom)
				(hide yes)
			)
		)
		(property "Datasheet" ""
			(at 397.51 106.68 0)
			(effects
				(font
					(size 1.27 1.27)
					(thickness 0.15)
				)
				(justify left bottom)
				(hide yes)
			)
		)
		(property "Description" ""
			(at 388.62 93.98 0)
			(effects
				(font
					(size 1.27 1.27)
				)
				(hide yes)
			)
		)
		(property "Author" "Antmicro"
			(at 397.51 101.6 0)
			(effects
				(font
					(size 1.27 1.27)
					(thickness 0.15)
				)
				(justify left bottom)
				(hide yes)
			)
		)
		(property "License" "Apache-2.0"
			(at 397.51 104.14 0)
			(effects
				(font
					(size 1.27 1.27)
					(thickness 0.15)
				)
				(justify left bottom)
				(hide yes)
			)
		)
		(pin "1"
		)
		(instances
			(project "OCuLink to 10GbE adapter"
				(path ""
					(reference "#PWR0173")
					(unit 1)
				)
			)
		)
	)
	(symbol
		(lib_id "antmicroCapacitors0402:C_1u_25V_0402")
		(at 308.61 73.66 90)
		(unit 1)
		(exclude_from_sim no)
		(in_bom yes)
		(on_board yes)
		(dnp no)
		(property "Reference" "C106"
			(at 310.642 69.85 90)
			(effects
				(font
					(size 1.27 1.27)
					(thickness 0.15)
				)
				(justify right)
			)
		)
		(property "Value" "C_1u_25V_0402"
			(at 318.77 53.34 0)
			(effects
				(font
					(size 1.27 1.27)
					(thickness 0.15)
				)
				(justify left bottom)
				(hide yes)
			)
		)
		(property "Footprint" "antmicro-footprints:C_0402_1005Metric"
			(at 321.31 53.34 0)
			(effects
				(font
					(size 1.27 1.27)
					(thickness 0.15)
				)
				(justify left bottom)
				(hide yes)
			)
		)
		(property "Datasheet" "https://www.murata.com/products/productdetail?partno=GRM155R61E105KE11%23"
			(at 323.85 53.34 0)
			(effects
				(font
					(size 1.27 1.27)
					(thickness 0.15)
				)
				(justify left bottom)
				(hide yes)
			)
		)
		(property "Description" "SMD Multilayer Ceramic Capacitor, 1 µF, 25 V, 0402 [1005 Metric], ± 10%, X5R, GRM Series"
			(at 308.61 73.66 0)
			(effects
				(font
					(size 1.27 1.27)
				)
				(hide yes)
			)
		)
		(property "MPN" "GRM155R61E105KE11J"
			(at 326.39 53.34 0)
			(effects
				(font
					(size 1.27 1.27)
					(thickness 0.15)
				)
				(justify left bottom)
				(hide yes)
			)
		)
		(property "Manufacturer" "Murata"
			(at 328.93 53.34 0)
			(effects
				(font
					(size 1.27 1.27)
					(thickness 0.15)
				)
				(justify left bottom)
				(hide yes)
			)
		)
		(property "License" "Apache-2.0"
			(at 331.47 53.34 0)
			(effects
				(font
					(size 1.27 1.27)
					(thickness 0.15)
				)
				(justify left bottom)
				(hide yes)
			)
		)
		(property "Author" "Antmicro"
			(at 334.01 53.34 0)
			(effects
				(font
					(size 1.27 1.27)
					(thickness 0.15)
				)
				(justify left bottom)
				(hide yes)
			)
		)
		(property "Val" "1u"
			(at 310.642 72.39 90)
			(effects
				(font
					(size 1.27 1.27)
					(thickness 0.15)
				)
				(justify right)
			)
		)
		(property "Voltage" "25V"
			(at 336.55 53.34 0)
			(effects
				(font
					(size 1.27 1.27)
				)
				(justify left bottom)
				(hide yes)
			)
		)
		(property "Dielectric" "X5R"
			(at 339.09 53.34 0)
			(effects
				(font
					(size 1.27 1.27)
				)
				(justify left bottom)
				(hide yes)
			)
		)
		(pin "2"
		)
		(pin "1"
		)
		(instances
			(project "OCuLink to 10GbE adapter"
				(path ""
					(reference "C106")
					(unit 1)
				)
			)
		)
	)
	(symbol
		(lib_id "antmicropower:GND")
		(at 270.51 152.4 0)
		(unit 1)
		(exclude_from_sim no)
		(in_bom yes)
		(on_board yes)
		(dnp no)
		(property "Reference" "#PWR0206"
			(at 279.4 154.94 0)
			(effects
				(font
					(size 1.27 1.27)
					(thickness 0.15)
				)
				(justify left bottom)
				(hide yes)
			)
		)
		(property "Value" "GND"
			(at 270.51 156.21 0)
			(effects
				(font
					(size 1.27 1.27)
					(thickness 0.15)
				)
			)
		)
		(property "Footprint" ""
			(at 279.4 160.02 0)
			(effects
				(font
					(size 1.27 1.27)
					(thickness 0.15)
				)
				(justify left bottom)
				(hide yes)
			)
		)
		(property "Datasheet" ""
			(at 279.4 165.1 0)
			(effects
				(font
					(size 1.27 1.27)
					(thickness 0.15)
				)
				(justify left bottom)
				(hide yes)
			)
		)
		(property "Description" ""
			(at 270.51 152.4 0)
			(effects
				(font
					(size 1.27 1.27)
				)
				(hide yes)
			)
		)
		(property "Author" "Antmicro"
			(at 279.4 160.02 0)
			(effects
				(font
					(size 1.27 1.27)
					(thickness 0.15)
				)
				(justify left bottom)
				(hide yes)
			)
		)
		(property "License" "Apache-2.0"
			(at 279.4 162.56 0)
			(effects
				(font
					(size 1.27 1.27)
					(thickness 0.15)
				)
				(justify left bottom)
				(hide yes)
			)
		)
		(pin "1"
		)
		(instances
			(project "OCuLink to 10GbE adapter"
				(path ""
					(reference "#PWR0206")
					(unit 1)
				)
			)
		)
	)
	(symbol
		(lib_id "antmicroCapacitors0402:C_1u_25V_0402")
		(at 106.68 207.01 90)
		(unit 1)
		(exclude_from_sim no)
		(in_bom yes)
		(on_board yes)
		(dnp no)
		(property "Reference" "C183"
			(at 108.712 203.2 90)
			(effects
				(font
					(size 1.27 1.27)
					(thickness 0.15)
				)
				(justify right)
			)
		)
		(property "Value" "C_1u_25V_0402"
			(at 116.84 186.69 0)
			(effects
				(font
					(size 1.27 1.27)
					(thickness 0.15)
				)
				(justify left bottom)
				(hide yes)
			)
		)
		(property "Footprint" "antmicro-footprints:C_0402_1005Metric"
			(at 119.38 186.69 0)
			(effects
				(font
					(size 1.27 1.27)
					(thickness 0.15)
				)
				(justify left bottom)
				(hide yes)
			)
		)
		(property "Datasheet" "https://www.murata.com/products/productdetail?partno=GRM155R61E105KE11%23"
			(at 121.92 186.69 0)
			(effects
				(font
					(size 1.27 1.27)
					(thickness 0.15)
				)
				(justify left bottom)
				(hide yes)
			)
		)
		(property "Description" "SMD Multilayer Ceramic Capacitor, 1 µF, 25 V, 0402 [1005 Metric], ± 10%, X5R, GRM Series"
			(at 106.68 207.01 0)
			(effects
				(font
					(size 1.27 1.27)
				)
				(hide yes)
			)
		)
		(property "MPN" "GRM155R61E105KE11J"
			(at 124.46 186.69 0)
			(effects
				(font
					(size 1.27 1.27)
					(thickness 0.15)
				)
				(justify left bottom)
				(hide yes)
			)
		)
		(property "Manufacturer" "Murata"
			(at 127 186.69 0)
			(effects
				(font
					(size 1.27 1.27)
					(thickness 0.15)
				)
				(justify left bottom)
				(hide yes)
			)
		)
		(property "License" "Apache-2.0"
			(at 129.54 186.69 0)
			(effects
				(font
					(size 1.27 1.27)
					(thickness 0.15)
				)
				(justify left bottom)
				(hide yes)
			)
		)
		(property "Author" "Antmicro"
			(at 132.08 186.69 0)
			(effects
				(font
					(size 1.27 1.27)
					(thickness 0.15)
				)
				(justify left bottom)
				(hide yes)
			)
		)
		(property "Val" "1u"
			(at 108.712 205.74 90)
			(effects
				(font
					(size 1.27 1.27)
					(thickness 0.15)
				)
				(justify right)
			)
		)
		(property "Voltage" "25V"
			(at 134.62 186.69 0)
			(effects
				(font
					(size 1.27 1.27)
				)
				(justify left bottom)
				(hide yes)
			)
		)
		(property "Dielectric" "X5R"
			(at 137.16 186.69 0)
			(effects
				(font
					(size 1.27 1.27)
				)
				(justify left bottom)
				(hide yes)
			)
		)
		(pin "2"
		)
		(pin "1"
		)
		(instances
			(project "OCuLink to 10GbE adapter"
				(path ""
					(reference "C183")
					(unit 1)
				)
			)
		)
	)
	(symbol
		(lib_id "antmicroCapacitors0402:C_1u_25V_0402")
		(at 106.68 52.07 90)
		(unit 1)
		(exclude_from_sim no)
		(in_bom yes)
		(on_board yes)
		(dnp no)
		(property "Reference" "C85"
			(at 108.712 48.26 90)
			(effects
				(font
					(size 1.27 1.27)
					(thickness 0.15)
				)
				(justify right)
			)
		)
		(property "Value" "C_1u_25V_0402"
			(at 116.84 31.75 0)
			(effects
				(font
					(size 1.27 1.27)
					(thickness 0.15)
				)
				(justify left bottom)
				(hide yes)
			)
		)
		(property "Footprint" "antmicro-footprints:C_0402_1005Metric"
			(at 119.38 31.75 0)
			(effects
				(font
					(size 1.27 1.27)
					(thickness 0.15)
				)
				(justify left bottom)
				(hide yes)
			)
		)
		(property "Datasheet" "https://www.murata.com/products/productdetail?partno=GRM155R61E105KE11%23"
			(at 121.92 31.75 0)
			(effects
				(font
					(size 1.27 1.27)
					(thickness 0.15)
				)
				(justify left bottom)
				(hide yes)
			)
		)
		(property "Description" "SMD Multilayer Ceramic Capacitor, 1 µF, 25 V, 0402 [1005 Metric], ± 10%, X5R, GRM Series"
			(at 106.68 52.07 0)
			(effects
				(font
					(size 1.27 1.27)
				)
				(hide yes)
			)
		)
		(property "MPN" "GRM155R61E105KE11J"
			(at 124.46 31.75 0)
			(effects
				(font
					(size 1.27 1.27)
					(thickness 0.15)
				)
				(justify left bottom)
				(hide yes)
			)
		)
		(property "Manufacturer" "Murata"
			(at 127 31.75 0)
			(effects
				(font
					(size 1.27 1.27)
					(thickness 0.15)
				)
				(justify left bottom)
				(hide yes)
			)
		)
		(property "License" "Apache-2.0"
			(at 129.54 31.75 0)
			(effects
				(font
					(size 1.27 1.27)
					(thickness 0.15)
				)
				(justify left bottom)
				(hide yes)
			)
		)
		(property "Author" "Antmicro"
			(at 132.08 31.75 0)
			(effects
				(font
					(size 1.27 1.27)
					(thickness 0.15)
				)
				(justify left bottom)
				(hide yes)
			)
		)
		(property "Val" "1u"
			(at 108.712 50.8 90)
			(effects
				(font
					(size 1.27 1.27)
					(thickness 0.15)
				)
				(justify right)
			)
		)
		(property "Voltage" "25V"
			(at 134.62 31.75 0)
			(effects
				(font
					(size 1.27 1.27)
				)
				(justify left bottom)
				(hide yes)
			)
		)
		(property "Dielectric" "X5R"
			(at 137.16 31.75 0)
			(effects
				(font
					(size 1.27 1.27)
				)
				(justify left bottom)
				(hide yes)
			)
		)
		(pin "2"
		)
		(pin "1"
		)
		(instances
			(project "OCuLink to 10GbE adapter"
				(path ""
					(reference "C85")
					(unit 1)
				)
			)
		)
	)
	(symbol
		(lib_id "antmicropower:GND")
		(at 71.12 156.21 0)
		(unit 1)
		(exclude_from_sim no)
		(in_bom yes)
		(on_board yes)
		(dnp no)
		(property "Reference" "#PWR0216"
			(at 80.01 158.75 0)
			(effects
				(font
					(size 1.27 1.27)
					(thickness 0.15)
				)
				(justify left bottom)
				(hide yes)
			)
		)
		(property "Value" "GND"
			(at 71.12 160.02 0)
			(effects
				(font
					(size 1.27 1.27)
					(thickness 0.15)
				)
			)
		)
		(property "Footprint" ""
			(at 80.01 163.83 0)
			(effects
				(font
					(size 1.27 1.27)
					(thickness 0.15)
				)
				(justify left bottom)
				(hide yes)
			)
		)
		(property "Datasheet" ""
			(at 80.01 168.91 0)
			(effects
				(font
					(size 1.27 1.27)
					(thickness 0.15)
				)
				(justify left bottom)
				(hide yes)
			)
		)
		(property "Description" ""
			(at 71.12 156.21 0)
			(effects
				(font
					(size 1.27 1.27)
				)
				(hide yes)
			)
		)
		(property "Author" "Antmicro"
			(at 80.01 163.83 0)
			(effects
				(font
					(size 1.27 1.27)
					(thickness 0.15)
				)
				(justify left bottom)
				(hide yes)
			)
		)
		(property "License" "Apache-2.0"
			(at 80.01 166.37 0)
			(effects
				(font
					(size 1.27 1.27)
					(thickness 0.15)
				)
				(justify left bottom)
				(hide yes)
			)
		)
		(pin "1"
		)
		(instances
			(project "OCuLink to 10GbE adapter"
				(path ""
					(reference "#PWR0216")
					(unit 1)
				)
			)
		)
	)
	(symbol
		(lib_id "antmicropower:GND")
		(at 353.06 54.61 0)
		(unit 1)
		(exclude_from_sim no)
		(in_bom yes)
		(on_board yes)
		(dnp no)
		(property "Reference" "#PWR0127"
			(at 361.95 57.15 0)
			(effects
				(font
					(size 1.27 1.27)
					(thickness 0.15)
				)
				(justify left bottom)
				(hide yes)
			)
		)
		(property "Value" "GND"
			(at 353.06 58.42 0)
			(effects
				(font
					(size 1.27 1.27)
					(thickness 0.15)
				)
			)
		)
		(property "Footprint" ""
			(at 361.95 62.23 0)
			(effects
				(font
					(size 1.27 1.27)
					(thickness 0.15)
				)
				(justify left bottom)
				(hide yes)
			)
		)
		(property "Datasheet" ""
			(at 361.95 67.31 0)
			(effects
				(font
					(size 1.27 1.27)
					(thickness 0.15)
				)
				(justify left bottom)
				(hide yes)
			)
		)
		(property "Description" ""
			(at 353.06 54.61 0)
			(effects
				(font
					(size 1.27 1.27)
				)
				(hide yes)
			)
		)
		(property "Author" "Antmicro"
			(at 361.95 62.23 0)
			(effects
				(font
					(size 1.27 1.27)
					(thickness 0.15)
				)
				(justify left bottom)
				(hide yes)
			)
		)
		(property "License" "Apache-2.0"
			(at 361.95 64.77 0)
			(effects
				(font
					(size 1.27 1.27)
					(thickness 0.15)
				)
				(justify left bottom)
				(hide yes)
			)
		)
		(pin "1"
		)
		(instances
			(project "OCuLink to 10GbE adapter"
				(path ""
					(reference "#PWR0127")
					(unit 1)
				)
			)
		)
	)
	(symbol
		(lib_id "antmicroCapacitors0603:C_22u_16V_0603")
		(at 388.62 91.44 90)
		(unit 1)
		(exclude_from_sim no)
		(in_bom yes)
		(on_board yes)
		(dnp no)
		(fields_autoplaced yes)
		(property "Reference" "C126"
			(at 391.16 87.6236 90)
			(effects
				(font
					(size 1.27 1.27)
					(thickness 0.15)
				)
				(justify right)
			)
		)
		(property "Value" "C_22u_16V_0603"
			(at 398.78 71.12 0)
			(effects
				(font
					(size 1.27 1.27)
					(thickness 0.15)
				)
				(justify left bottom)
				(hide yes)
			)
		)
		(property "Footprint" "antmicro-footprints:C_0603_1608Metric_EIA"
			(at 401.32 71.12 0)
			(effects
				(font
					(size 1.27 1.27)
					(thickness 0.15)
				)
				(justify left bottom)
				(hide yes)
			)
		)
		(property "Datasheet" "https://product.samsungsem.com/mlcc/CL10A226MO7JZN.do"
			(at 403.86 71.12 0)
			(effects
				(font
					(size 1.27 1.27)
					(thickness 0.15)
				)
				(justify left bottom)
				(hide yes)
			)
		)
		(property "Description" "SMD Multilayer Ceramic Capacitor"
			(at 388.62 91.44 0)
			(effects
				(font
					(size 1.27 1.27)
				)
				(hide yes)
			)
		)
		(property "MPN" "CL10A226MO7JZNC"
			(at 406.4 71.12 0)
			(effects
				(font
					(size 1.27 1.27)
					(thickness 0.15)
				)
				(justify left bottom)
				(hide yes)
			)
		)
		(property "Manufacturer" "Samsung Electro-Mechanics"
			(at 408.94 71.12 0)
			(effects
				(font
					(size 1.27 1.27)
					(thickness 0.15)
				)
				(justify left bottom)
				(hide yes)
			)
		)
		(property "License" "Apache-2.0"
			(at 411.48 71.12 0)
			(effects
				(font
					(size 1.27 1.27)
					(thickness 0.15)
				)
				(justify left bottom)
				(hide yes)
			)
		)
		(property "Author" "Antmicro"
			(at 414.02 71.12 0)
			(effects
				(font
					(size 1.27 1.27)
					(thickness 0.15)
				)
				(justify left bottom)
				(hide yes)
			)
		)
		(property "Val" "22u"
			(at 391.16 90.1636 90)
			(effects
				(font
					(size 1.27 1.27)
					(thickness 0.15)
				)
				(justify right)
			)
		)
		(property "Voltage" "16V"
			(at 416.56 71.12 0)
			(effects
				(font
					(size 1.27 1.27)
				)
				(justify left bottom)
				(hide yes)
			)
		)
		(property "Dielectric" ""
			(at 419.1 71.12 0)
			(effects
				(font
					(size 1.27 1.27)
				)
				(justify left bottom)
				(hide yes)
			)
		)
		(pin "1"
		)
		(pin "2"
		)
		(instances
			(project "OCuLink to 10GbE adapter"
				(path ""
					(reference "C126")
					(unit 1)
				)
			)
		)
	)
	(symbol
		(lib_id "antmicroCapacitors0603:C_22u_16V_0603")
		(at 370.84 91.44 90)
		(unit 1)
		(exclude_from_sim no)
		(in_bom yes)
		(on_board yes)
		(dnp no)
		(fields_autoplaced yes)
		(property "Reference" "C124"
			(at 373.38 87.6236 90)
			(effects
				(font
					(size 1.27 1.27)
					(thickness 0.15)
				)
				(justify right)
			)
		)
		(property "Value" "C_22u_16V_0603"
			(at 381 71.12 0)
			(effects
				(font
					(size 1.27 1.27)
					(thickness 0.15)
				)
				(justify left bottom)
				(hide yes)
			)
		)
		(property "Footprint" "antmicro-footprints:C_0603_1608Metric_EIA"
			(at 383.54 71.12 0)
			(effects
				(font
					(size 1.27 1.27)
					(thickness 0.15)
				)
				(justify left bottom)
				(hide yes)
			)
		)
		(property "Datasheet" "https://product.samsungsem.com/mlcc/CL10A226MO7JZN.do"
			(at 386.08 71.12 0)
			(effects
				(font
					(size 1.27 1.27)
					(thickness 0.15)
				)
				(justify left bottom)
				(hide yes)
			)
		)
		(property "Description" "SMD Multilayer Ceramic Capacitor"
			(at 370.84 91.44 0)
			(effects
				(font
					(size 1.27 1.27)
				)
				(hide yes)
			)
		)
		(property "MPN" "CL10A226MO7JZNC"
			(at 388.62 71.12 0)
			(effects
				(font
					(size 1.27 1.27)
					(thickness 0.15)
				)
				(justify left bottom)
				(hide yes)
			)
		)
		(property "Manufacturer" "Samsung Electro-Mechanics"
			(at 391.16 71.12 0)
			(effects
				(font
					(size 1.27 1.27)
					(thickness 0.15)
				)
				(justify left bottom)
				(hide yes)
			)
		)
		(property "License" "Apache-2.0"
			(at 393.7 71.12 0)
			(effects
				(font
					(size 1.27 1.27)
					(thickness 0.15)
				)
				(justify left bottom)
				(hide yes)
			)
		)
		(property "Author" "Antmicro"
			(at 396.24 71.12 0)
			(effects
				(font
					(size 1.27 1.27)
					(thickness 0.15)
				)
				(justify left bottom)
				(hide yes)
			)
		)
		(property "Val" "22u"
			(at 373.38 90.1636 90)
			(effects
				(font
					(size 1.27 1.27)
					(thickness 0.15)
				)
				(justify right)
			)
		)
		(property "Voltage" "16V"
			(at 398.78 71.12 0)
			(effects
				(font
					(size 1.27 1.27)
				)
				(justify left bottom)
				(hide yes)
			)
		)
		(property "Dielectric" ""
			(at 401.32 71.12 0)
			(effects
				(font
					(size 1.27 1.27)
				)
				(justify left bottom)
				(hide yes)
			)
		)
		(pin "1"
		)
		(pin "2"
		)
		(instances
			(project "OCuLink to 10GbE adapter"
				(path ""
					(reference "C124")
					(unit 1)
				)
			)
		)
	)
	(symbol
		(lib_id "antmicroCapacitors0402:C_1u_25V_0402")
		(at 88.9 207.01 90)
		(unit 1)
		(exclude_from_sim no)
		(in_bom yes)
		(on_board yes)
		(dnp no)
		(property "Reference" "C181"
			(at 90.932 203.2 90)
			(effects
				(font
					(size 1.27 1.27)
					(thickness 0.15)
				)
				(justify right)
			)
		)
		(property "Value" "C_1u_25V_0402"
			(at 99.06 186.69 0)
			(effects
				(font
					(size 1.27 1.27)
					(thickness 0.15)
				)
				(justify left bottom)
				(hide yes)
			)
		)
		(property "Footprint" "antmicro-footprints:C_0402_1005Metric"
			(at 101.6 186.69 0)
			(effects
				(font
					(size 1.27 1.27)
					(thickness 0.15)
				)
				(justify left bottom)
				(hide yes)
			)
		)
		(property "Datasheet" "https://www.murata.com/products/productdetail?partno=GRM155R61E105KE11%23"
			(at 104.14 186.69 0)
			(effects
				(font
					(size 1.27 1.27)
					(thickness 0.15)
				)
				(justify left bottom)
				(hide yes)
			)
		)
		(property "Description" "SMD Multilayer Ceramic Capacitor, 1 µF, 25 V, 0402 [1005 Metric], ± 10%, X5R, GRM Series"
			(at 88.9 207.01 0)
			(effects
				(font
					(size 1.27 1.27)
				)
				(hide yes)
			)
		)
		(property "MPN" "GRM155R61E105KE11J"
			(at 106.68 186.69 0)
			(effects
				(font
					(size 1.27 1.27)
					(thickness 0.15)
				)
				(justify left bottom)
				(hide yes)
			)
		)
		(property "Manufacturer" "Murata"
			(at 109.22 186.69 0)
			(effects
				(font
					(size 1.27 1.27)
					(thickness 0.15)
				)
				(justify left bottom)
				(hide yes)
			)
		)
		(property "License" "Apache-2.0"
			(at 111.76 186.69 0)
			(effects
				(font
					(size 1.27 1.27)
					(thickness 0.15)
				)
				(justify left bottom)
				(hide yes)
			)
		)
		(property "Author" "Antmicro"
			(at 114.3 186.69 0)
			(effects
				(font
					(size 1.27 1.27)
					(thickness 0.15)
				)
				(justify left bottom)
				(hide yes)
			)
		)
		(property "Val" "1u"
			(at 90.932 205.74 90)
			(effects
				(font
					(size 1.27 1.27)
					(thickness 0.15)
				)
				(justify right)
			)
		)
		(property "Voltage" "25V"
			(at 116.84 186.69 0)
			(effects
				(font
					(size 1.27 1.27)
				)
				(justify left bottom)
				(hide yes)
			)
		)
		(property "Dielectric" "X5R"
			(at 119.38 186.69 0)
			(effects
				(font
					(size 1.27 1.27)
				)
				(justify left bottom)
				(hide yes)
			)
		)
		(pin "2"
		)
		(pin "1"
		)
		(instances
			(project "OCuLink to 10GbE adapter"
				(path ""
					(reference "C181")
					(unit 1)
				)
			)
		)
	)
	(symbol
		(lib_id "antmicroCapacitors0402:C_1u_25V_0402")
		(at 115.57 127 90)
		(unit 1)
		(exclude_from_sim no)
		(in_bom yes)
		(on_board yes)
		(dnp no)
		(property "Reference" "C145"
			(at 117.348 123.19 90)
			(effects
				(font
					(size 1.27 1.27)
					(thickness 0.15)
				)
				(justify right)
			)
		)
		(property "Value" "C_1u_25V_0402"
			(at 125.73 106.68 0)
			(effects
				(font
					(size 1.27 1.27)
					(thickness 0.15)
				)
				(justify left bottom)
				(hide yes)
			)
		)
		(property "Footprint" "antmicro-footprints:C_0402_1005Metric"
			(at 128.27 106.68 0)
			(effects
				(font
					(size 1.27 1.27)
					(thickness 0.15)
				)
				(justify left bottom)
				(hide yes)
			)
		)
		(property "Datasheet" "https://www.murata.com/products/productdetail?partno=GRM155R61E105KE11%23"
			(at 130.81 106.68 0)
			(effects
				(font
					(size 1.27 1.27)
					(thickness 0.15)
				)
				(justify left bottom)
				(hide yes)
			)
		)
		(property "Description" "SMD Multilayer Ceramic Capacitor, 1 µF, 25 V, 0402 [1005 Metric], ± 10%, X5R, GRM Series"
			(at 115.57 127 0)
			(effects
				(font
					(size 1.27 1.27)
				)
				(hide yes)
			)
		)
		(property "MPN" "GRM155R61E105KE11J"
			(at 133.35 106.68 0)
			(effects
				(font
					(size 1.27 1.27)
					(thickness 0.15)
				)
				(justify left bottom)
				(hide yes)
			)
		)
		(property "Manufacturer" "Murata"
			(at 135.89 106.68 0)
			(effects
				(font
					(size 1.27 1.27)
					(thickness 0.15)
				)
				(justify left bottom)
				(hide yes)
			)
		)
		(property "License" "Apache-2.0"
			(at 138.43 106.68 0)
			(effects
				(font
					(size 1.27 1.27)
					(thickness 0.15)
				)
				(justify left bottom)
				(hide yes)
			)
		)
		(property "Author" "Antmicro"
			(at 140.97 106.68 0)
			(effects
				(font
					(size 1.27 1.27)
					(thickness 0.15)
				)
				(justify left bottom)
				(hide yes)
			)
		)
		(property "Val" "1u"
			(at 117.348 125.73 90)
			(effects
				(font
					(size 1.27 1.27)
					(thickness 0.15)
				)
				(justify right)
			)
		)
		(property "Voltage" "25V"
			(at 143.51 106.68 0)
			(effects
				(font
					(size 1.27 1.27)
				)
				(justify left bottom)
				(hide yes)
			)
		)
		(property "Dielectric" "X5R"
			(at 146.05 106.68 0)
			(effects
				(font
					(size 1.27 1.27)
				)
				(justify left bottom)
				(hide yes)
			)
		)
		(pin "2"
		)
		(pin "1"
		)
		(instances
			(project "OCuLink to 10GbE adapter"
				(path ""
					(reference "C145")
					(unit 1)
				)
			)
		)
	)
	(symbol
		(lib_id "antmicropower:PWR_FLAG")
		(at 66.04 198.12 0)
		(unit 1)
		(exclude_from_sim no)
		(in_bom yes)
		(on_board yes)
		(dnp no)
		(fields_autoplaced yes)
		(property "Reference" "#FLG017"
			(at 66.04 196.215 0)
			(effects
				(font
					(size 1.27 1.27)
				)
				(hide yes)
			)
		)
		(property "Value" "PWR_FLAG"
			(at 66.04 193.04 0)
			(effects
				(font
					(size 1.27 1.27)
				)
			)
		)
		(property "Footprint" ""
			(at 66.04 198.12 0)
			(effects
				(font
					(size 1.27 1.27)
				)
				(hide yes)
			)
		)
		(property "Datasheet" ""
			(at 66.04 198.12 0)
			(effects
				(font
					(size 1.27 1.27)
				)
				(hide yes)
			)
		)
		(property "Description" ""
			(at 66.04 200.66 0)
			(effects
				(font
					(size 1.27 1.27)
				)
				(justify left bottom)
				(hide yes)
			)
		)
		(pin "1"
		)
		(instances
			(project "OCuLink to 10GbE adapter"
				(path ""
					(reference "#FLG017")
					(unit 1)
				)
			)
		)
	)
	(symbol
		(lib_id "antmicropower:GND")
		(at 115.57 54.61 0)
		(unit 1)
		(exclude_from_sim no)
		(in_bom yes)
		(on_board yes)
		(dnp no)
		(property "Reference" "#PWR0120"
			(at 124.46 57.15 0)
			(effects
				(font
					(size 1.27 1.27)
					(thickness 0.15)
				)
				(justify left bottom)
				(hide yes)
			)
		)
		(property "Value" "GND"
			(at 115.57 58.42 0)
			(effects
				(font
					(size 1.27 1.27)
					(thickness 0.15)
				)
			)
		)
		(property "Footprint" ""
			(at 124.46 62.23 0)
			(effects
				(font
					(size 1.27 1.27)
					(thickness 0.15)
				)
				(justify left bottom)
				(hide yes)
			)
		)
		(property "Datasheet" ""
			(at 124.46 67.31 0)
			(effects
				(font
					(size 1.27 1.27)
					(thickness 0.15)
				)
				(justify left bottom)
				(hide yes)
			)
		)
		(property "Description" ""
			(at 115.57 54.61 0)
			(effects
				(font
					(size 1.27 1.27)
				)
				(hide yes)
			)
		)
		(property "Author" "Antmicro"
			(at 124.46 62.23 0)
			(effects
				(font
					(size 1.27 1.27)
					(thickness 0.15)
				)
				(justify left bottom)
				(hide yes)
			)
		)
		(property "License" "Apache-2.0"
			(at 124.46 64.77 0)
			(effects
				(font
					(size 1.27 1.27)
					(thickness 0.15)
				)
				(justify left bottom)
				(hide yes)
			)
		)
		(pin "1"
		)
		(instances
			(project "OCuLink to 10GbE adapter"
				(path ""
					(reference "#PWR0120")
					(unit 1)
				)
			)
		)
	)
	(symbol
		(lib_id "antmicropower:GND")
		(at 299.72 93.98 0)
		(unit 1)
		(exclude_from_sim no)
		(in_bom yes)
		(on_board yes)
		(dnp no)
		(property "Reference" "#PWR0164"
			(at 308.61 96.52 0)
			(effects
				(font
					(size 1.27 1.27)
					(thickness 0.15)
				)
				(justify left bottom)
				(hide yes)
			)
		)
		(property "Value" "GND"
			(at 299.72 97.79 0)
			(effects
				(font
					(size 1.27 1.27)
					(thickness 0.15)
				)
			)
		)
		(property "Footprint" ""
			(at 308.61 101.6 0)
			(effects
				(font
					(size 1.27 1.27)
					(thickness 0.15)
				)
				(justify left bottom)
				(hide yes)
			)
		)
		(property "Datasheet" ""
			(at 308.61 106.68 0)
			(effects
				(font
					(size 1.27 1.27)
					(thickness 0.15)
				)
				(justify left bottom)
				(hide yes)
			)
		)
		(property "Description" ""
			(at 299.72 93.98 0)
			(effects
				(font
					(size 1.27 1.27)
				)
				(hide yes)
			)
		)
		(property "Author" "Antmicro"
			(at 308.61 101.6 0)
			(effects
				(font
					(size 1.27 1.27)
					(thickness 0.15)
				)
				(justify left bottom)
				(hide yes)
			)
		)
		(property "License" "Apache-2.0"
			(at 308.61 104.14 0)
			(effects
				(font
					(size 1.27 1.27)
					(thickness 0.15)
				)
				(justify left bottom)
				(hide yes)
			)
		)
		(pin "1"
		)
		(instances
			(project "OCuLink to 10GbE adapter"
				(path ""
					(reference "#PWR0164")
					(unit 1)
				)
			)
		)
	)
	(symbol
		(lib_id "antmicroCapacitorsmisc:C_100u_0805")
		(at 62.23 180.34 90)
		(unit 1)
		(exclude_from_sim no)
		(in_bom yes)
		(on_board yes)
		(dnp no)
		(property "Reference" "C173"
			(at 64.008 176.53 90)
			(effects
				(font
					(size 1.27 1.27)
					(thickness 0.15)
				)
				(justify right)
			)
		)
		(property "Value" "C_100u_0805"
			(at 72.39 160.02 0)
			(effects
				(font
					(size 1.27 1.27)
					(thickness 0.15)
				)
				(justify left bottom)
				(hide yes)
			)
		)
		(property "Footprint" "antmicro-footprints:C_0805_2012Metric"
			(at 74.93 160.02 0)
			(effects
				(font
					(size 1.27 1.27)
					(thickness 0.15)
				)
				(justify left bottom)
				(hide yes)
			)
		)
		(property "Datasheet" "https://www.murata.com/products/productdetail?partno=GRM21BR60J107ME15%23"
			(at 77.47 160.02 0)
			(effects
				(font
					(size 1.27 1.27)
					(thickness 0.15)
				)
				(justify left bottom)
				(hide yes)
			)
		)
		(property "Description" "SMD Multilayer Ceramic Capacitor, 100 µF, 6.3 V, 0805 [2012 Metric], ± 20%, X5R, GRM Series"
			(at 62.23 180.34 0)
			(effects
				(font
					(size 1.27 1.27)
				)
				(hide yes)
			)
		)
		(property "MPN" "GRM21BR60J107ME15L"
			(at 80.01 160.02 0)
			(effects
				(font
					(size 1.27 1.27)
					(thickness 0.15)
				)
				(justify left bottom)
				(hide yes)
			)
		)
		(property "Manufacturer" "Murata"
			(at 82.55 160.02 0)
			(effects
				(font
					(size 1.27 1.27)
					(thickness 0.15)
				)
				(justify left bottom)
				(hide yes)
			)
		)
		(property "License" "Apache-2.0"
			(at 85.09 160.02 0)
			(effects
				(font
					(size 1.27 1.27)
					(thickness 0.15)
				)
				(justify left bottom)
				(hide yes)
			)
		)
		(property "Author" "Antmicro"
			(at 87.63 160.02 0)
			(effects
				(font
					(size 1.27 1.27)
					(thickness 0.15)
				)
				(justify left bottom)
				(hide yes)
			)
		)
		(property "Val" "100u"
			(at 64.008 179.07 90)
			(effects
				(font
					(size 1.27 1.27)
					(thickness 0.15)
				)
				(justify right)
			)
		)
		(property "Voltage" ""
			(at 90.17 160.02 0)
			(effects
				(font
					(size 1.27 1.27)
				)
				(justify left bottom)
				(hide yes)
			)
		)
		(property "Dielectric" ""
			(at 92.71 160.02 0)
			(effects
				(font
					(size 1.27 1.27)
				)
				(justify left bottom)
				(hide yes)
			)
		)
		(property "Public" "False"
			(at 95.25 160.02 0)
			(effects
				(font
					(size 1.27 1.27)
				)
				(justify left bottom)
				(hide yes)
			)
		)
		(pin "1"
		)
		(pin "2"
		)
		(instances
			(project "OCuLink to 10GbE adapter"
				(path ""
					(reference "C173")
					(unit 1)
				)
			)
		)
	)
	(symbol
		(lib_id "antmicroCapacitors0603:C_22u_16V_0603")
		(at 353.06 130.81 90)
		(unit 1)
		(exclude_from_sim no)
		(in_bom yes)
		(on_board yes)
		(dnp no)
		(fields_autoplaced yes)
		(property "Reference" "C151"
			(at 355.6 126.9936 90)
			(effects
				(font
					(size 1.27 1.27)
					(thickness 0.15)
				)
				(justify right)
			)
		)
		(property "Value" "C_22u_16V_0603"
			(at 363.22 110.49 0)
			(effects
				(font
					(size 1.27 1.27)
					(thickness 0.15)
				)
				(justify left bottom)
				(hide yes)
			)
		)
		(property "Footprint" "antmicro-footprints:C_0603_1608Metric_EIA"
			(at 365.76 110.49 0)
			(effects
				(font
					(size 1.27 1.27)
					(thickness 0.15)
				)
				(justify left bottom)
				(hide yes)
			)
		)
		(property "Datasheet" "https://product.samsungsem.com/mlcc/CL10A226MO7JZN.do"
			(at 368.3 110.49 0)
			(effects
				(font
					(size 1.27 1.27)
					(thickness 0.15)
				)
				(justify left bottom)
				(hide yes)
			)
		)
		(property "Description" "SMD Multilayer Ceramic Capacitor"
			(at 353.06 130.81 0)
			(effects
				(font
					(size 1.27 1.27)
				)
				(hide yes)
			)
		)
		(property "MPN" "CL10A226MO7JZNC"
			(at 370.84 110.49 0)
			(effects
				(font
					(size 1.27 1.27)
					(thickness 0.15)
				)
				(justify left bottom)
				(hide yes)
			)
		)
		(property "Manufacturer" "Samsung Electro-Mechanics"
			(at 373.38 110.49 0)
			(effects
				(font
					(size 1.27 1.27)
					(thickness 0.15)
				)
				(justify left bottom)
				(hide yes)
			)
		)
		(property "License" "Apache-2.0"
			(at 375.92 110.49 0)
			(effects
				(font
					(size 1.27 1.27)
					(thickness 0.15)
				)
				(justify left bottom)
				(hide yes)
			)
		)
		(property "Author" "Antmicro"
			(at 378.46 110.49 0)
			(effects
				(font
					(size 1.27 1.27)
					(thickness 0.15)
				)
				(justify left bottom)
				(hide yes)
			)
		)
		(property "Val" "22u"
			(at 355.6 129.5336 90)
			(effects
				(font
					(size 1.27 1.27)
					(thickness 0.15)
				)
				(justify right)
			)
		)
		(property "Voltage" "16V"
			(at 381 110.49 0)
			(effects
				(font
					(size 1.27 1.27)
				)
				(justify left bottom)
				(hide yes)
			)
		)
		(property "Dielectric" ""
			(at 383.54 110.49 0)
			(effects
				(font
					(size 1.27 1.27)
				)
				(justify left bottom)
				(hide yes)
			)
		)
		(pin "1"
		)
		(pin "2"
		)
		(instances
			(project "OCuLink to 10GbE adapter"
				(path ""
					(reference "C151")
					(unit 1)
				)
			)
		)
	)
	(symbol
		(lib_id "antmicroCapacitors0402:C_1u_25V_0402")
		(at 335.28 91.44 90)
		(unit 1)
		(exclude_from_sim no)
		(in_bom yes)
		(on_board yes)
		(dnp no)
		(property "Reference" "C121"
			(at 337.312 87.63 90)
			(effects
				(font
					(size 1.27 1.27)
					(thickness 0.15)
				)
				(justify right)
			)
		)
		(property "Value" "C_1u_25V_0402"
			(at 345.44 71.12 0)
			(effects
				(font
					(size 1.27 1.27)
					(thickness 0.15)
				)
				(justify left bottom)
				(hide yes)
			)
		)
		(property "Footprint" "antmicro-footprints:C_0402_1005Metric"
			(at 347.98 71.12 0)
			(effects
				(font
					(size 1.27 1.27)
					(thickness 0.15)
				)
				(justify left bottom)
				(hide yes)
			)
		)
		(property "Datasheet" "https://www.murata.com/products/productdetail?partno=GRM155R61E105KE11%23"
			(at 350.52 71.12 0)
			(effects
				(font
					(size 1.27 1.27)
					(thickness 0.15)
				)
				(justify left bottom)
				(hide yes)
			)
		)
		(property "Description" "SMD Multilayer Ceramic Capacitor, 1 µF, 25 V, 0402 [1005 Metric], ± 10%, X5R, GRM Series"
			(at 335.28 91.44 0)
			(effects
				(font
					(size 1.27 1.27)
				)
				(hide yes)
			)
		)
		(property "MPN" "GRM155R61E105KE11J"
			(at 353.06 71.12 0)
			(effects
				(font
					(size 1.27 1.27)
					(thickness 0.15)
				)
				(justify left bottom)
				(hide yes)
			)
		)
		(property "Manufacturer" "Murata"
			(at 355.6 71.12 0)
			(effects
				(font
					(size 1.27 1.27)
					(thickness 0.15)
				)
				(justify left bottom)
				(hide yes)
			)
		)
		(property "License" "Apache-2.0"
			(at 358.14 71.12 0)
			(effects
				(font
					(size 1.27 1.27)
					(thickness 0.15)
				)
				(justify left bottom)
				(hide yes)
			)
		)
		(property "Author" "Antmicro"
			(at 360.68 71.12 0)
			(effects
				(font
					(size 1.27 1.27)
					(thickness 0.15)
				)
				(justify left bottom)
				(hide yes)
			)
		)
		(property "Val" "1u"
			(at 337.312 90.17 90)
			(effects
				(font
					(size 1.27 1.27)
					(thickness 0.15)
				)
				(justify right)
			)
		)
		(property "Voltage" "25V"
			(at 363.22 71.12 0)
			(effects
				(font
					(size 1.27 1.27)
				)
				(justify left bottom)
				(hide yes)
			)
		)
		(property "Dielectric" "X5R"
			(at 365.76 71.12 0)
			(effects
				(font
					(size 1.27 1.27)
				)
				(justify left bottom)
				(hide yes)
			)
		)
		(pin "2"
		)
		(pin "1"
		)
		(instances
			(project "OCuLink to 10GbE adapter"
				(path ""
					(reference "C121")
					(unit 1)
				)
			)
		)
	)
	(symbol
		(lib_id "antmicroCapacitors0402:C_100n_0402")
		(at 41.91 127 90)
		(unit 1)
		(exclude_from_sim no)
		(in_bom yes)
		(on_board yes)
		(dnp no)
		(property "Reference" "C138"
			(at 43.942 123.19 90)
			(effects
				(font
					(size 1.27 1.27)
					(thickness 0.15)
				)
				(justify right)
			)
		)
		(property "Value" "C_100n_0402"
			(at 64.77 111.76 0)
			(effects
				(font
					(size 1.27 1.27)
					(thickness 0.15)
				)
				(justify left bottom)
				(hide yes)
			)
		)
		(property "Footprint" "antmicro-footprints:C_0402_1005Metric"
			(at 67.31 111.76 0)
			(effects
				(font
					(size 1.27 1.27)
					(thickness 0.15)
				)
				(justify left bottom)
				(hide yes)
			)
		)
		(property "Datasheet" "https://www.murata.com/products/productdetail?partno=GRM155R61H104KE14%23"
			(at 69.85 111.76 0)
			(effects
				(font
					(size 1.27 1.27)
					(thickness 0.15)
				)
				(justify left bottom)
				(hide yes)
			)
		)
		(property "Description" "SMD Multilayer Ceramic Capacitor, 0.1 µF, 50 V, 0402 [1005 Metric], ± 10%, X5R, GRM Series"
			(at 41.91 127 0)
			(effects
				(font
					(size 1.27 1.27)
				)
				(hide yes)
			)
		)
		(property "MPN" "GRM155R61H104KE14D"
			(at 72.39 111.76 0)
			(effects
				(font
					(size 1.27 1.27)
					(thickness 0.15)
				)
				(justify left bottom)
				(hide yes)
			)
		)
		(property "Val" "100n"
			(at 43.942 125.73 90)
			(effects
				(font
					(size 1.27 1.27)
					(thickness 0.15)
				)
				(justify right)
			)
		)
		(property "Voltage" "50V"
			(at 52.07 111.76 0)
			(effects
				(font
					(size 1.27 1.27)
					(thickness 0.15)
				)
				(justify left bottom)
				(hide yes)
			)
		)
		(property "Dielectric" "X5R"
			(at 54.61 111.76 0)
			(effects
				(font
					(size 1.27 1.27)
					(thickness 0.15)
				)
				(justify left bottom)
				(hide yes)
			)
		)
		(property "Manufacturer" "Murata"
			(at 57.15 111.76 0)
			(effects
				(font
					(size 1.27 1.27)
					(thickness 0.15)
				)
				(justify left bottom)
				(hide yes)
			)
		)
		(property "License" "Apache-2.0"
			(at 59.69 111.76 0)
			(effects
				(font
					(size 1.27 1.27)
					(thickness 0.15)
				)
				(justify left bottom)
				(hide yes)
			)
		)
		(property "Author" "Antmicro"
			(at 62.23 111.76 0)
			(effects
				(font
					(size 1.27 1.27)
					(thickness 0.15)
				)
				(justify left bottom)
				(hide yes)
			)
		)
		(pin "2"
		)
		(pin "1"
		)
		(instances
			(project "OCuLink to 10GbE adapter"
				(path ""
					(reference "C138")
					(unit 1)
				)
			)
		)
	)
	(symbol
		(lib_id "antmicroCapacitorspol:C_Pol_470u_6.3V_Vishay-TR3-D")
		(at 21.59 148.59 270)
		(unit 1)
		(exclude_from_sim no)
		(in_bom yes)
		(on_board yes)
		(dnp no)
		(property "Reference" "C156"
			(at 23.876 149.352 90)
			(effects
				(font
					(size 1.27 1.27)
					(thickness 0.15)
				)
				(justify left)
			)
		)
		(property "Value" "C_Pol_470u_6.3V_Vishay-TR3-D"
			(at 19.05 162.56 0)
			(effects
				(font
					(size 1.27 1.27)
					(thickness 0.15)
				)
				(justify left bottom)
				(hide yes)
			)
		)
		(property "Footprint" "antmicro-footprints:C_Pol_EIA-D"
			(at 13.97 162.56 0)
			(effects
				(font
					(size 1.27 1.27)
					(thickness 0.15)
				)
				(justify left bottom)
				(hide yes)
			)
		)
		(property "Datasheet" "https://www.vishay.com/docs/40080/tr3.pdf"
			(at 11.43 162.56 0)
			(effects
				(font
					(size 1.27 1.27)
					(thickness 0.15)
				)
				(justify left bottom)
				(hide yes)
			)
		)
		(property "Description" "470 µF Molded Tantalum Capacitors 6.3 V 2917 (7343 Metric) 200mOhm"
			(at 21.59 148.59 0)
			(effects
				(font
					(size 1.27 1.27)
				)
				(hide yes)
			)
		)
		(property "Val" "470u"
			(at 23.876 151.892 90)
			(effects
				(font
					(size 1.27 1.27)
					(thickness 0.15)
				)
				(justify left)
			)
		)
		(property "MPN" "TR3D477M6R3C0200"
			(at 8.89 162.56 0)
			(effects
				(font
					(size 1.27 1.27)
					(thickness 0.15)
				)
				(justify left bottom)
				(hide yes)
			)
		)
		(property "Manufacturer" "Vishay"
			(at 6.35 162.56 0)
			(effects
				(font
					(size 1.27 1.27)
					(thickness 0.15)
				)
				(justify left bottom)
				(hide yes)
			)
		)
		(property "License" "Apache-2.0"
			(at 3.81 162.56 0)
			(effects
				(font
					(size 1.27 1.27)
					(thickness 0.15)
				)
				(justify left bottom)
				(hide yes)
			)
		)
		(property "Author" "Antmicro"
			(at 1.27 162.56 0)
			(effects
				(font
					(size 1.27 1.27)
					(thickness 0.15)
				)
				(justify left bottom)
				(hide yes)
			)
		)
		(property "Voltage" "6.3V"
			(at -1.27 162.56 0)
			(effects
				(font
					(size 1.27 1.27)
				)
				(justify left bottom)
				(hide yes)
			)
		)
		(property "Dielectric" "template_dielectric"
			(at -3.81 162.56 0)
			(effects
				(font
					(size 1.27 1.27)
				)
				(justify left bottom)
				(hide yes)
			)
		)
		(pin "2"
		)
		(pin "1"
		)
		(instances
			(project "OCuLink to 10GbE adapter"
				(path ""
					(reference "C156")
					(unit 1)
				)
			)
		)
	)
	(symbol
		(lib_id "antmicropower:GND")
		(at 370.84 93.98 0)
		(unit 1)
		(exclude_from_sim no)
		(in_bom yes)
		(on_board yes)
		(dnp no)
		(property "Reference" "#PWR0171"
			(at 379.73 96.52 0)
			(effects
				(font
					(size 1.27 1.27)
					(thickness 0.15)
				)
				(justify left bottom)
				(hide yes)
			)
		)
		(property "Value" "GND"
			(at 370.84 97.79 0)
			(effects
				(font
					(size 1.27 1.27)
					(thickness 0.15)
				)
			)
		)
		(property "Footprint" ""
			(at 379.73 101.6 0)
			(effects
				(font
					(size 1.27 1.27)
					(thickness 0.15)
				)
				(justify left bottom)
				(hide yes)
			)
		)
		(property "Datasheet" ""
			(at 379.73 106.68 0)
			(effects
				(font
					(size 1.27 1.27)
					(thickness 0.15)
				)
				(justify left bottom)
				(hide yes)
			)
		)
		(property "Description" ""
			(at 370.84 93.98 0)
			(effects
				(font
					(size 1.27 1.27)
				)
				(hide yes)
			)
		)
		(property "Author" "Antmicro"
			(at 379.73 101.6 0)
			(effects
				(font
					(size 1.27 1.27)
					(thickness 0.15)
				)
				(justify left bottom)
				(hide yes)
			)
		)
		(property "License" "Apache-2.0"
			(at 379.73 104.14 0)
			(effects
				(font
					(size 1.27 1.27)
					(thickness 0.15)
				)
				(justify left bottom)
				(hide yes)
			)
		)
		(pin "1"
		)
		(instances
			(project "OCuLink to 10GbE adapter"
				(path ""
					(reference "#PWR0171")
					(unit 1)
				)
			)
		)
	)
	(symbol
		(lib_id "antmicropower:GND")
		(at 31.75 156.21 0)
		(unit 1)
		(exclude_from_sim no)
		(in_bom yes)
		(on_board yes)
		(dnp no)
		(property "Reference" "#PWR0212"
			(at 40.64 158.75 0)
			(effects
				(font
					(size 1.27 1.27)
					(thickness 0.15)
				)
				(justify left bottom)
				(hide yes)
			)
		)
		(property "Value" "GND"
			(at 31.75 160.02 0)
			(effects
				(font
					(size 1.27 1.27)
					(thickness 0.15)
				)
			)
		)
		(property "Footprint" ""
			(at 40.64 163.83 0)
			(effects
				(font
					(size 1.27 1.27)
					(thickness 0.15)
				)
				(justify left bottom)
				(hide yes)
			)
		)
		(property "Datasheet" ""
			(at 40.64 168.91 0)
			(effects
				(font
					(size 1.27 1.27)
					(thickness 0.15)
				)
				(justify left bottom)
				(hide yes)
			)
		)
		(property "Description" ""
			(at 31.75 156.21 0)
			(effects
				(font
					(size 1.27 1.27)
				)
				(hide yes)
			)
		)
		(property "Author" "Antmicro"
			(at 40.64 163.83 0)
			(effects
				(font
					(size 1.27 1.27)
					(thickness 0.15)
				)
				(justify left bottom)
				(hide yes)
			)
		)
		(property "License" "Apache-2.0"
			(at 40.64 166.37 0)
			(effects
				(font
					(size 1.27 1.27)
					(thickness 0.15)
				)
				(justify left bottom)
				(hide yes)
			)
		)
		(pin "1"
		)
		(instances
			(project "OCuLink to 10GbE adapter"
				(path ""
					(reference "#PWR0212")
					(unit 1)
				)
			)
		)
	)
	(symbol
		(lib_id "antmicroCapacitors0603:C_22u_16V_0603")
		(at 379.73 130.81 90)
		(unit 1)
		(exclude_from_sim no)
		(in_bom yes)
		(on_board yes)
		(dnp no)
		(fields_autoplaced yes)
		(property "Reference" "C154"
			(at 382.27 126.9936 90)
			(effects
				(font
					(size 1.27 1.27)
					(thickness 0.15)
				)
				(justify right)
			)
		)
		(property "Value" "C_22u_16V_0603"
			(at 389.89 110.49 0)
			(effects
				(font
					(size 1.27 1.27)
					(thickness 0.15)
				)
				(justify left bottom)
				(hide yes)
			)
		)
		(property "Footprint" "antmicro-footprints:C_0603_1608Metric_EIA"
			(at 392.43 110.49 0)
			(effects
				(font
					(size 1.27 1.27)
					(thickness 0.15)
				)
				(justify left bottom)
				(hide yes)
			)
		)
		(property "Datasheet" "https://product.samsungsem.com/mlcc/CL10A226MO7JZN.do"
			(at 394.97 110.49 0)
			(effects
				(font
					(size 1.27 1.27)
					(thickness 0.15)
				)
				(justify left bottom)
				(hide yes)
			)
		)
		(property "Description" "SMD Multilayer Ceramic Capacitor"
			(at 379.73 130.81 0)
			(effects
				(font
					(size 1.27 1.27)
				)
				(hide yes)
			)
		)
		(property "MPN" "CL10A226MO7JZNC"
			(at 397.51 110.49 0)
			(effects
				(font
					(size 1.27 1.27)
					(thickness 0.15)
				)
				(justify left bottom)
				(hide yes)
			)
		)
		(property "Manufacturer" "Samsung Electro-Mechanics"
			(at 400.05 110.49 0)
			(effects
				(font
					(size 1.27 1.27)
					(thickness 0.15)
				)
				(justify left bottom)
				(hide yes)
			)
		)
		(property "License" "Apache-2.0"
			(at 402.59 110.49 0)
			(effects
				(font
					(size 1.27 1.27)
					(thickness 0.15)
				)
				(justify left bottom)
				(hide yes)
			)
		)
		(property "Author" "Antmicro"
			(at 405.13 110.49 0)
			(effects
				(font
					(size 1.27 1.27)
					(thickness 0.15)
				)
				(justify left bottom)
				(hide yes)
			)
		)
		(property "Val" "22u"
			(at 382.27 129.5336 90)
			(effects
				(font
					(size 1.27 1.27)
					(thickness 0.15)
				)
				(justify right)
			)
		)
		(property "Voltage" "16V"
			(at 407.67 110.49 0)
			(effects
				(font
					(size 1.27 1.27)
				)
				(justify left bottom)
				(hide yes)
			)
		)
		(property "Dielectric" ""
			(at 410.21 110.49 0)
			(effects
				(font
					(size 1.27 1.27)
				)
				(justify left bottom)
				(hide yes)
			)
		)
		(pin "1"
		)
		(pin "2"
		)
		(instances
			(project "OCuLink to 10GbE adapter"
				(path ""
					(reference "C154")
					(unit 1)
				)
			)
		)
	)
	(symbol
		(lib_id "antmicroCapacitors0402:C_1u_25V_0402")
		(at 115.57 180.34 90)
		(unit 1)
		(exclude_from_sim no)
		(in_bom yes)
		(on_board yes)
		(dnp no)
		(property "Reference" "C178"
			(at 117.602 176.53 90)
			(effects
				(font
					(size 1.27 1.27)
					(thickness 0.15)
				)
				(justify right)
			)
		)
		(property "Value" "C_1u_25V_0402"
			(at 125.73 160.02 0)
			(effects
				(font
					(size 1.27 1.27)
					(thickness 0.15)
				)
				(justify left bottom)
				(hide yes)
			)
		)
		(property "Footprint" "antmicro-footprints:C_0402_1005Metric"
			(at 128.27 160.02 0)
			(effects
				(font
					(size 1.27 1.27)
					(thickness 0.15)
				)
				(justify left bottom)
				(hide yes)
			)
		)
		(property "Datasheet" "https://www.murata.com/products/productdetail?partno=GRM155R61E105KE11%23"
			(at 130.81 160.02 0)
			(effects
				(font
					(size 1.27 1.27)
					(thickness 0.15)
				)
				(justify left bottom)
				(hide yes)
			)
		)
		(property "Description" "SMD Multilayer Ceramic Capacitor, 1 µF, 25 V, 0402 [1005 Metric], ± 10%, X5R, GRM Series"
			(at 115.57 180.34 0)
			(effects
				(font
					(size 1.27 1.27)
				)
				(hide yes)
			)
		)
		(property "MPN" "GRM155R61E105KE11J"
			(at 133.35 160.02 0)
			(effects
				(font
					(size 1.27 1.27)
					(thickness 0.15)
				)
				(justify left bottom)
				(hide yes)
			)
		)
		(property "Manufacturer" "Murata"
			(at 135.89 160.02 0)
			(effects
				(font
					(size 1.27 1.27)
					(thickness 0.15)
				)
				(justify left bottom)
				(hide yes)
			)
		)
		(property "License" "Apache-2.0"
			(at 138.43 160.02 0)
			(effects
				(font
					(size 1.27 1.27)
					(thickness 0.15)
				)
				(justify left bottom)
				(hide yes)
			)
		)
		(property "Author" "Antmicro"
			(at 140.97 160.02 0)
			(effects
				(font
					(size 1.27 1.27)
					(thickness 0.15)
				)
				(justify left bottom)
				(hide yes)
			)
		)
		(property "Val" "1u"
			(at 117.602 179.07 90)
			(effects
				(font
					(size 1.27 1.27)
					(thickness 0.15)
				)
				(justify right)
			)
		)
		(property "Voltage" "25V"
			(at 143.51 160.02 0)
			(effects
				(font
					(size 1.27 1.27)
				)
				(justify left bottom)
				(hide yes)
			)
		)
		(property "Dielectric" "X5R"
			(at 146.05 160.02 0)
			(effects
				(font
					(size 1.27 1.27)
				)
				(justify left bottom)
				(hide yes)
			)
		)
		(pin "2"
		)
		(pin "1"
		)
		(instances
			(project "OCuLink to 10GbE adapter"
				(path ""
					(reference "C178")
					(unit 1)
				)
			)
		)
	)
	(symbol
		(lib_id "antmicroCapacitors0402:C_1u_25V_0402")
		(at 299.72 91.44 90)
		(unit 1)
		(exclude_from_sim no)
		(in_bom yes)
		(on_board yes)
		(dnp no)
		(property "Reference" "C117"
			(at 301.752 87.63 90)
			(effects
				(font
					(size 1.27 1.27)
					(thickness 0.15)
				)
				(justify right)
			)
		)
		(property "Value" "C_1u_25V_0402"
			(at 309.88 71.12 0)
			(effects
				(font
					(size 1.27 1.27)
					(thickness 0.15)
				)
				(justify left bottom)
				(hide yes)
			)
		)
		(property "Footprint" "antmicro-footprints:C_0402_1005Metric"
			(at 312.42 71.12 0)
			(effects
				(font
					(size 1.27 1.27)
					(thickness 0.15)
				)
				(justify left bottom)
				(hide yes)
			)
		)
		(property "Datasheet" "https://www.murata.com/products/productdetail?partno=GRM155R61E105KE11%23"
			(at 314.96 71.12 0)
			(effects
				(font
					(size 1.27 1.27)
					(thickness 0.15)
				)
				(justify left bottom)
				(hide yes)
			)
		)
		(property "Description" "SMD Multilayer Ceramic Capacitor, 1 µF, 25 V, 0402 [1005 Metric], ± 10%, X5R, GRM Series"
			(at 299.72 91.44 0)
			(effects
				(font
					(size 1.27 1.27)
				)
				(hide yes)
			)
		)
		(property "MPN" "GRM155R61E105KE11J"
			(at 317.5 71.12 0)
			(effects
				(font
					(size 1.27 1.27)
					(thickness 0.15)
				)
				(justify left bottom)
				(hide yes)
			)
		)
		(property "Manufacturer" "Murata"
			(at 320.04 71.12 0)
			(effects
				(font
					(size 1.27 1.27)
					(thickness 0.15)
				)
				(justify left bottom)
				(hide yes)
			)
		)
		(property "License" "Apache-2.0"
			(at 322.58 71.12 0)
			(effects
				(font
					(size 1.27 1.27)
					(thickness 0.15)
				)
				(justify left bottom)
				(hide yes)
			)
		)
		(property "Author" "Antmicro"
			(at 325.12 71.12 0)
			(effects
				(font
					(size 1.27 1.27)
					(thickness 0.15)
				)
				(justify left bottom)
				(hide yes)
			)
		)
		(property "Val" "1u"
			(at 301.752 90.17 90)
			(effects
				(font
					(size 1.27 1.27)
					(thickness 0.15)
				)
				(justify right)
			)
		)
		(property "Voltage" "25V"
			(at 327.66 71.12 0)
			(effects
				(font
					(size 1.27 1.27)
				)
				(justify left bottom)
				(hide yes)
			)
		)
		(property "Dielectric" "X5R"
			(at 330.2 71.12 0)
			(effects
				(font
					(size 1.27 1.27)
				)
				(justify left bottom)
				(hide yes)
			)
		)
		(pin "2"
		)
		(pin "1"
		)
		(instances
			(project "OCuLink to 10GbE adapter"
				(path ""
					(reference "C117")
					(unit 1)
				)
			)
		)
	)
	(symbol
		(lib_id "antmicropower:GND")
		(at 335.28 54.61 0)
		(unit 1)
		(exclude_from_sim no)
		(in_bom yes)
		(on_board yes)
		(dnp no)
		(property "Reference" "#PWR0125"
			(at 344.17 57.15 0)
			(effects
				(font
					(size 1.27 1.27)
					(thickness 0.15)
				)
				(justify left bottom)
				(hide yes)
			)
		)
		(property "Value" "GND"
			(at 335.28 58.42 0)
			(effects
				(font
					(size 1.27 1.27)
					(thickness 0.15)
				)
			)
		)
		(property "Footprint" ""
			(at 344.17 62.23 0)
			(effects
				(font
					(size 1.27 1.27)
					(thickness 0.15)
				)
				(justify left bottom)
				(hide yes)
			)
		)
		(property "Datasheet" ""
			(at 344.17 67.31 0)
			(effects
				(font
					(size 1.27 1.27)
					(thickness 0.15)
				)
				(justify left bottom)
				(hide yes)
			)
		)
		(property "Description" ""
			(at 335.28 54.61 0)
			(effects
				(font
					(size 1.27 1.27)
				)
				(hide yes)
			)
		)
		(property "Author" "Antmicro"
			(at 344.17 62.23 0)
			(effects
				(font
					(size 1.27 1.27)
					(thickness 0.15)
				)
				(justify left bottom)
				(hide yes)
			)
		)
		(property "License" "Apache-2.0"
			(at 344.17 64.77 0)
			(effects
				(font
					(size 1.27 1.27)
					(thickness 0.15)
				)
				(justify left bottom)
				(hide yes)
			)
		)
		(pin "1"
		)
		(instances
			(project "OCuLink to 10GbE adapter"
				(path ""
					(reference "#PWR0125")
					(unit 1)
				)
			)
		)
	)
	(symbol
		(lib_id "antmicroCapacitors0402:C_1u_25V_0402")
		(at 353.06 113.03 90)
		(unit 1)
		(exclude_from_sim no)
		(in_bom yes)
		(on_board yes)
		(dnp no)
		(property "Reference" "C135"
			(at 355.092 109.22 90)
			(effects
				(font
					(size 1.27 1.27)
					(thickness 0.15)
				)
				(justify right)
			)
		)
		(property "Value" "C_1u_25V_0402"
			(at 363.22 92.71 0)
			(effects
				(font
					(size 1.27 1.27)
					(thickness 0.15)
				)
				(justify left bottom)
				(hide yes)
			)
		)
		(property "Footprint" "antmicro-footprints:C_0402_1005Metric"
			(at 365.76 92.71 0)
			(effects
				(font
					(size 1.27 1.27)
					(thickness 0.15)
				)
				(justify left bottom)
				(hide yes)
			)
		)
		(property "Datasheet" "https://www.murata.com/products/productdetail?partno=GRM155R61E105KE11%23"
			(at 368.3 92.71 0)
			(effects
				(font
					(size 1.27 1.27)
					(thickness 0.15)
				)
				(justify left bottom)
				(hide yes)
			)
		)
		(property "Description" "SMD Multilayer Ceramic Capacitor, 1 µF, 25 V, 0402 [1005 Metric], ± 10%, X5R, GRM Series"
			(at 353.06 113.03 0)
			(effects
				(font
					(size 1.27 1.27)
				)
				(hide yes)
			)
		)
		(property "MPN" "GRM155R61E105KE11J"
			(at 370.84 92.71 0)
			(effects
				(font
					(size 1.27 1.27)
					(thickness 0.15)
				)
				(justify left bottom)
				(hide yes)
			)
		)
		(property "Manufacturer" "Murata"
			(at 373.38 92.71 0)
			(effects
				(font
					(size 1.27 1.27)
					(thickness 0.15)
				)
				(justify left bottom)
				(hide yes)
			)
		)
		(property "License" "Apache-2.0"
			(at 375.92 92.71 0)
			(effects
				(font
					(size 1.27 1.27)
					(thickness 0.15)
				)
				(justify left bottom)
				(hide yes)
			)
		)
		(property "Author" "Antmicro"
			(at 378.46 92.71 0)
			(effects
				(font
					(size 1.27 1.27)
					(thickness 0.15)
				)
				(justify left bottom)
				(hide yes)
			)
		)
		(property "Val" "1u"
			(at 355.092 111.76 90)
			(effects
				(font
					(size 1.27 1.27)
					(thickness 0.15)
				)
				(justify right)
			)
		)
		(property "Voltage" "25V"
			(at 381 92.71 0)
			(effects
				(font
					(size 1.27 1.27)
				)
				(justify left bottom)
				(hide yes)
			)
		)
		(property "Dielectric" "X5R"
			(at 383.54 92.71 0)
			(effects
				(font
					(size 1.27 1.27)
				)
				(justify left bottom)
				(hide yes)
			)
		)
		(pin "2"
		)
		(pin "1"
		)
		(instances
			(project "OCuLink to 10GbE adapter"
				(path ""
					(reference "C135")
					(unit 1)
				)
			)
		)
	)
	(symbol
		(lib_id "antmicroCapacitors0402:C_1u_25V_0402")
		(at 115.57 52.07 90)
		(unit 1)
		(exclude_from_sim no)
		(in_bom yes)
		(on_board yes)
		(dnp no)
		(property "Reference" "C86"
			(at 117.602 48.26 90)
			(effects
				(font
					(size 1.27 1.27)
					(thickness 0.15)
				)
				(justify right)
			)
		)
		(property "Value" "C_1u_25V_0402"
			(at 125.73 31.75 0)
			(effects
				(font
					(size 1.27 1.27)
					(thickness 0.15)
				)
				(justify left bottom)
				(hide yes)
			)
		)
		(property "Footprint" "antmicro-footprints:C_0402_1005Metric"
			(at 128.27 31.75 0)
			(effects
				(font
					(size 1.27 1.27)
					(thickness 0.15)
				)
				(justify left bottom)
				(hide yes)
			)
		)
		(property "Datasheet" "https://www.murata.com/products/productdetail?partno=GRM155R61E105KE11%23"
			(at 130.81 31.75 0)
			(effects
				(font
					(size 1.27 1.27)
					(thickness 0.15)
				)
				(justify left bottom)
				(hide yes)
			)
		)
		(property "Description" "SMD Multilayer Ceramic Capacitor, 1 µF, 25 V, 0402 [1005 Metric], ± 10%, X5R, GRM Series"
			(at 115.57 52.07 0)
			(effects
				(font
					(size 1.27 1.27)
				)
				(hide yes)
			)
		)
		(property "MPN" "GRM155R61E105KE11J"
			(at 133.35 31.75 0)
			(effects
				(font
					(size 1.27 1.27)
					(thickness 0.15)
				)
				(justify left bottom)
				(hide yes)
			)
		)
		(property "Manufacturer" "Murata"
			(at 135.89 31.75 0)
			(effects
				(font
					(size 1.27 1.27)
					(thickness 0.15)
				)
				(justify left bottom)
				(hide yes)
			)
		)
		(property "License" "Apache-2.0"
			(at 138.43 31.75 0)
			(effects
				(font
					(size 1.27 1.27)
					(thickness 0.15)
				)
				(justify left bottom)
				(hide yes)
			)
		)
		(property "Author" "Antmicro"
			(at 140.97 31.75 0)
			(effects
				(font
					(size 1.27 1.27)
					(thickness 0.15)
				)
				(justify left bottom)
				(hide yes)
			)
		)
		(property "Val" "1u"
			(at 117.602 50.8 90)
			(effects
				(font
					(size 1.27 1.27)
					(thickness 0.15)
				)
				(justify right)
			)
		)
		(property "Voltage" "25V"
			(at 143.51 31.75 0)
			(effects
				(font
					(size 1.27 1.27)
				)
				(justify left bottom)
				(hide yes)
			)
		)
		(property "Dielectric" "X5R"
			(at 146.05 31.75 0)
			(effects
				(font
					(size 1.27 1.27)
				)
				(justify left bottom)
				(hide yes)
			)
		)
		(pin "2"
		)
		(pin "1"
		)
		(instances
			(project "OCuLink to 10GbE adapter"
				(path ""
					(reference "C86")
					(unit 1)
				)
			)
		)
	)
	(symbol
		(lib_id "antmicroFixedInductors:L_4u7_1.55A_Bourns-SRP2512A")
		(at 44.45 199.39 0)
		(unit 1)
		(exclude_from_sim no)
		(in_bom yes)
		(on_board yes)
		(dnp no)
		(fields_autoplaced yes)
		(property "Reference" "L9"
			(at 46.99 194.31 0)
			(effects
				(font
					(size 1.27 1.27)
					(thickness 0.15)
				)
			)
		)
		(property "Value" "L_4u7_1.55A_Bourns-SRP2512A"
			(at 59.69 204.47 0)
			(effects
				(font
					(size 1.27 1.27)
					(thickness 0.15)
				)
				(justify left bottom)
				(hide yes)
			)
		)
		(property "Footprint" "antmicro-footprints:L_Bourns-SRP2512A"
			(at 59.69 207.01 0)
			(effects
				(font
					(size 1.27 1.27)
					(thickness 0.15)
				)
				(justify left bottom)
				(hide yes)
			)
		)
		(property "Datasheet" "https://www.bourns.com/docs/Product-Datasheets/srp2512a.pdf"
			(at 59.69 209.55 0)
			(effects
				(font
					(size 1.27 1.27)
					(thickness 0.15)
				)
				(justify left bottom)
				(hide yes)
			)
		)
		(property "Description" "4.7 µH Shielded Drum Core, Wirewound Inductor 1.55 A 235mOhm Max 1008 (2520 Metric)"
			(at 59.69 229.87 0)
			(effects
				(font
					(size 1.27 1.27)
				)
				(justify left bottom)
				(hide yes)
			)
		)
		(property "Val" "4u7/1.55A"
			(at 46.99 196.85 0)
			(effects
				(font
					(size 1.27 1.27)
					(thickness 0.15)
				)
			)
		)
		(property "Manufacturer" "Bourns"
			(at 59.69 212.09 0)
			(effects
				(font
					(size 1.27 1.27)
					(thickness 0.15)
				)
				(justify left bottom)
				(hide yes)
			)
		)
		(property "MPN" "SRP2512A-4R7M"
			(at 59.69 214.63 0)
			(effects
				(font
					(size 1.27 1.27)
					(thickness 0.15)
				)
				(justify left bottom)
				(hide yes)
			)
		)
		(property "ISat" "1.9 A"
			(at 59.69 217.17 0)
			(effects
				(font
					(size 1.27 1.27)
				)
				(justify left bottom)
				(hide yes)
			)
		)
		(property "IMax" "1.55 A"
			(at 59.69 219.71 0)
			(effects
				(font
					(size 1.27 1.27)
				)
				(justify left bottom)
				(hide yes)
			)
		)
		(property "Size" "2.5x2.0"
			(at 59.69 222.25 0)
			(effects
				(font
					(size 1.27 1.27)
				)
				(justify left bottom)
				(hide yes)
			)
		)
		(property "Author" "Antmicro"
			(at 59.69 224.79 0)
			(effects
				(font
					(size 1.27 1.27)
					(thickness 0.15)
				)
				(justify left bottom)
				(hide yes)
			)
		)
		(property "License" "Apache-2.0"
			(at 59.69 227.33 0)
			(effects
				(font
					(size 1.27 1.27)
					(thickness 0.15)
				)
				(justify left bottom)
				(hide yes)
			)
		)
		(pin "2"
		)
		(pin "1"
		)
		(instances
			(project "oculink-to-10gbe-adapter"
				(path ""
					(reference "L9")
					(unit 1)
				)
			)
		)
	)
	(symbol
		(lib_id "antmicroCapacitors0603:C_10u_10V_X7R_0603")
		(at 299.72 130.81 90)
		(unit 1)
		(exclude_from_sim no)
		(in_bom yes)
		(on_board yes)
		(dnp no)
		(property "Reference" "C146"
			(at 301.752 127 90)
			(effects
				(font
					(size 1.27 1.27)
					(thickness 0.15)
				)
				(justify right)
			)
		)
		(property "Value" "C_10u_10V_X7R_0603"
			(at 309.88 115.57 0)
			(effects
				(font
					(size 1.27 1.27)
					(thickness 0.15)
				)
				(justify left bottom)
				(hide yes)
			)
		)
		(property "Footprint" "antmicro-footprints:C_0603_1608Metric"
			(at 312.42 115.57 0)
			(effects
				(font
					(size 1.27 1.27)
					(thickness 0.15)
				)
				(justify left bottom)
				(hide yes)
			)
		)
		(property "Datasheet" "https://www.murata.com/products/productdetail?partno=GRM188Z71A106KA73%23"
			(at 314.96 115.57 0)
			(effects
				(font
					(size 1.27 1.27)
					(thickness 0.15)
				)
				(justify left bottom)
				(hide yes)
			)
		)
		(property "Description" "SMD Multilayer Ceramic Capacitor,  10µF, 10V, 0603, ±10%, X7R"
			(at 299.72 130.81 0)
			(effects
				(font
					(size 1.27 1.27)
				)
				(hide yes)
			)
		)
		(property "MPN" "GRM188Z71A106KA73D"
			(at 317.5 115.57 0)
			(effects
				(font
					(size 1.27 1.27)
					(thickness 0.15)
				)
				(justify left bottom)
				(hide yes)
			)
		)
		(property "Val" "10u"
			(at 301.752 129.54 90)
			(effects
				(font
					(size 1.27 1.27)
					(thickness 0.15)
				)
				(justify right)
			)
		)
		(property "Voltage" "10V"
			(at 320.04 115.57 0)
			(effects
				(font
					(size 1.27 1.27)
					(thickness 0.15)
				)
				(justify left bottom)
				(hide yes)
			)
		)
		(property "Dielectric" "X7R"
			(at 322.58 115.57 0)
			(effects
				(font
					(size 1.27 1.27)
					(thickness 0.15)
				)
				(justify left bottom)
				(hide yes)
			)
		)
		(property "Manufacturer" "Murata"
			(at 325.12 115.57 0)
			(effects
				(font
					(size 1.27 1.27)
					(thickness 0.15)
				)
				(justify left bottom)
				(hide yes)
			)
		)
		(property "License" "Apache-2.0"
			(at 327.66 115.57 0)
			(effects
				(font
					(size 1.27 1.27)
					(thickness 0.15)
				)
				(justify left bottom)
				(hide yes)
			)
		)
		(property "Author" "Antmicro"
			(at 330.2 115.57 0)
			(effects
				(font
					(size 1.27 1.27)
					(thickness 0.15)
				)
				(justify left bottom)
				(hide yes)
			)
		)
		(pin "1"
		)
		(pin "2"
		)
		(instances
			(project ""
				(path ""
					(reference "C146")
					(unit 1)
				)
			)
		)
	)
	(symbol
		(lib_id "antmicropower:VCC")
		(at 276.86 78.74 0)
		(unit 1)
		(exclude_from_sim no)
		(in_bom yes)
		(on_board yes)
		(dnp no)
		(property "Reference" "#PWR0161"
			(at 276.86 82.55 0)
			(effects
				(font
					(size 1.27 1.27)
				)
				(hide yes)
			)
		)
		(property "Value" "VCCD"
			(at 276.86 74.93 0)
			(effects
				(font
					(size 1.27 1.27)
				)
			)
		)
		(property "Footprint" ""
			(at 276.86 78.74 0)
			(effects
				(font
					(size 1.27 1.27)
				)
				(hide yes)
			)
		)
		(property "Datasheet" ""
			(at 276.86 78.74 0)
			(effects
				(font
					(size 1.27 1.27)
				)
				(hide yes)
			)
		)
		(property "Description" ""
			(at 276.86 78.74 0)
			(effects
				(font
					(size 1.27 1.27)
				)
				(hide yes)
			)
		)
		(pin "1"
		)
		(instances
			(project "OCuLink to 10GbE adapter"
				(path ""
					(reference "#PWR0161")
					(unit 1)
				)
			)
		)
	)
	(symbol
		(lib_id "antmicroCapacitors0402:C_1u_25V_0402")
		(at 326.39 73.66 90)
		(unit 1)
		(exclude_from_sim no)
		(in_bom yes)
		(on_board yes)
		(dnp no)
		(property "Reference" "C108"
			(at 328.422 69.85 90)
			(effects
				(font
					(size 1.27 1.27)
					(thickness 0.15)
				)
				(justify right)
			)
		)
		(property "Value" "C_1u_25V_0402"
			(at 336.55 53.34 0)
			(effects
				(font
					(size 1.27 1.27)
					(thickness 0.15)
				)
				(justify left bottom)
				(hide yes)
			)
		)
		(property "Footprint" "antmicro-footprints:C_0402_1005Metric"
			(at 339.09 53.34 0)
			(effects
				(font
					(size 1.27 1.27)
					(thickness 0.15)
				)
				(justify left bottom)
				(hide yes)
			)
		)
		(property "Datasheet" "https://www.murata.com/products/productdetail?partno=GRM155R61E105KE11%23"
			(at 341.63 53.34 0)
			(effects
				(font
					(size 1.27 1.27)
					(thickness 0.15)
				)
				(justify left bottom)
				(hide yes)
			)
		)
		(property "Description" "SMD Multilayer Ceramic Capacitor, 1 µF, 25 V, 0402 [1005 Metric], ± 10%, X5R, GRM Series"
			(at 326.39 73.66 0)
			(effects
				(font
					(size 1.27 1.27)
				)
				(hide yes)
			)
		)
		(property "MPN" "GRM155R61E105KE11J"
			(at 344.17 53.34 0)
			(effects
				(font
					(size 1.27 1.27)
					(thickness 0.15)
				)
				(justify left bottom)
				(hide yes)
			)
		)
		(property "Manufacturer" "Murata"
			(at 346.71 53.34 0)
			(effects
				(font
					(size 1.27 1.27)
					(thickness 0.15)
				)
				(justify left bottom)
				(hide yes)
			)
		)
		(property "License" "Apache-2.0"
			(at 349.25 53.34 0)
			(effects
				(font
					(size 1.27 1.27)
					(thickness 0.15)
				)
				(justify left bottom)
				(hide yes)
			)
		)
		(property "Author" "Antmicro"
			(at 351.79 53.34 0)
			(effects
				(font
					(size 1.27 1.27)
					(thickness 0.15)
				)
				(justify left bottom)
				(hide yes)
			)
		)
		(property "Val" "1u"
			(at 328.422 72.39 90)
			(effects
				(font
					(size 1.27 1.27)
					(thickness 0.15)
				)
				(justify right)
			)
		)
		(property "Voltage" "25V"
			(at 354.33 53.34 0)
			(effects
				(font
					(size 1.27 1.27)
				)
				(justify left bottom)
				(hide yes)
			)
		)
		(property "Dielectric" "X5R"
			(at 356.87 53.34 0)
			(effects
				(font
					(size 1.27 1.27)
				)
				(justify left bottom)
				(hide yes)
			)
		)
		(pin "2"
		)
		(pin "1"
		)
		(instances
			(project "OCuLink to 10GbE adapter"
				(path ""
					(reference "C108")
					(unit 1)
				)
			)
		)
	)
	(symbol
		(lib_id "antmicropower:GND")
		(at 54.61 209.55 0)
		(unit 1)
		(exclude_from_sim no)
		(in_bom yes)
		(on_board yes)
		(dnp no)
		(property "Reference" "#PWR0233"
			(at 63.5 212.09 0)
			(effects
				(font
					(size 1.27 1.27)
					(thickness 0.15)
				)
				(justify left bottom)
				(hide yes)
			)
		)
		(property "Value" "GND"
			(at 54.61 213.36 0)
			(effects
				(font
					(size 1.27 1.27)
					(thickness 0.15)
				)
			)
		)
		(property "Footprint" ""
			(at 63.5 217.17 0)
			(effects
				(font
					(size 1.27 1.27)
					(thickness 0.15)
				)
				(justify left bottom)
				(hide yes)
			)
		)
		(property "Datasheet" ""
			(at 63.5 222.25 0)
			(effects
				(font
					(size 1.27 1.27)
					(thickness 0.15)
				)
				(justify left bottom)
				(hide yes)
			)
		)
		(property "Description" ""
			(at 54.61 209.55 0)
			(effects
				(font
					(size 1.27 1.27)
				)
				(hide yes)
			)
		)
		(property "Author" "Antmicro"
			(at 63.5 217.17 0)
			(effects
				(font
					(size 1.27 1.27)
					(thickness 0.15)
				)
				(justify left bottom)
				(hide yes)
			)
		)
		(property "License" "Apache-2.0"
			(at 63.5 219.71 0)
			(effects
				(font
					(size 1.27 1.27)
					(thickness 0.15)
				)
				(justify left bottom)
				(hide yes)
			)
		)
		(pin "1"
		)
		(instances
			(project "OCuLink to 10GbE adapter"
				(path ""
					(reference "#PWR0233")
					(unit 1)
				)
			)
		)
	)
	(symbol
		(lib_id "antmicroCapacitors0402:C_1u_25V_0402")
		(at 97.79 127 90)
		(unit 1)
		(exclude_from_sim no)
		(in_bom yes)
		(on_board yes)
		(dnp no)
		(property "Reference" "C143"
			(at 99.568 123.19 90)
			(effects
				(font
					(size 1.27 1.27)
					(thickness 0.15)
				)
				(justify right)
			)
		)
		(property "Value" "C_1u_25V_0402"
			(at 107.95 106.68 0)
			(effects
				(font
					(size 1.27 1.27)
					(thickness 0.15)
				)
				(justify left bottom)
				(hide yes)
			)
		)
		(property "Footprint" "antmicro-footprints:C_0402_1005Metric"
			(at 110.49 106.68 0)
			(effects
				(font
					(size 1.27 1.27)
					(thickness 0.15)
				)
				(justify left bottom)
				(hide yes)
			)
		)
		(property "Datasheet" "https://www.murata.com/products/productdetail?partno=GRM155R61E105KE11%23"
			(at 113.03 106.68 0)
			(effects
				(font
					(size 1.27 1.27)
					(thickness 0.15)
				)
				(justify left bottom)
				(hide yes)
			)
		)
		(property "Description" "SMD Multilayer Ceramic Capacitor, 1 µF, 25 V, 0402 [1005 Metric], ± 10%, X5R, GRM Series"
			(at 97.79 127 0)
			(effects
				(font
					(size 1.27 1.27)
				)
				(hide yes)
			)
		)
		(property "MPN" "GRM155R61E105KE11J"
			(at 115.57 106.68 0)
			(effects
				(font
					(size 1.27 1.27)
					(thickness 0.15)
				)
				(justify left bottom)
				(hide yes)
			)
		)
		(property "Manufacturer" "Murata"
			(at 118.11 106.68 0)
			(effects
				(font
					(size 1.27 1.27)
					(thickness 0.15)
				)
				(justify left bottom)
				(hide yes)
			)
		)
		(property "License" "Apache-2.0"
			(at 120.65 106.68 0)
			(effects
				(font
					(size 1.27 1.27)
					(thickness 0.15)
				)
				(justify left bottom)
				(hide yes)
			)
		)
		(property "Author" "Antmicro"
			(at 123.19 106.68 0)
			(effects
				(font
					(size 1.27 1.27)
					(thickness 0.15)
				)
				(justify left bottom)
				(hide yes)
			)
		)
		(property "Val" "1u"
			(at 99.568 125.73 90)
			(effects
				(font
					(size 1.27 1.27)
					(thickness 0.15)
				)
				(justify right)
			)
		)
		(property "Voltage" "25V"
			(at 125.73 106.68 0)
			(effects
				(font
					(size 1.27 1.27)
				)
				(justify left bottom)
				(hide yes)
			)
		)
		(property "Dielectric" "X5R"
			(at 128.27 106.68 0)
			(effects
				(font
					(size 1.27 1.27)
				)
				(justify left bottom)
				(hide yes)
			)
		)
		(pin "2"
		)
		(pin "1"
		)
		(instances
			(project "OCuLink to 10GbE adapter"
				(path ""
					(reference "C143")
					(unit 1)
				)
			)
		)
	)
	(symbol
		(lib_id "antmicroCapacitors0603:C_22u_16V_0603")
		(at 353.06 91.44 90)
		(unit 1)
		(exclude_from_sim no)
		(in_bom yes)
		(on_board yes)
		(dnp no)
		(fields_autoplaced yes)
		(property "Reference" "C122"
			(at 355.6 87.6236 90)
			(effects
				(font
					(size 1.27 1.27)
					(thickness 0.15)
				)
				(justify right)
			)
		)
		(property "Value" "C_22u_16V_0603"
			(at 363.22 71.12 0)
			(effects
				(font
					(size 1.27 1.27)
					(thickness 0.15)
				)
				(justify left bottom)
				(hide yes)
			)
		)
		(property "Footprint" "antmicro-footprints:C_0603_1608Metric_EIA"
			(at 365.76 71.12 0)
			(effects
				(font
					(size 1.27 1.27)
					(thickness 0.15)
				)
				(justify left bottom)
				(hide yes)
			)
		)
		(property "Datasheet" "https://product.samsungsem.com/mlcc/CL10A226MO7JZN.do"
			(at 368.3 71.12 0)
			(effects
				(font
					(size 1.27 1.27)
					(thickness 0.15)
				)
				(justify left bottom)
				(hide yes)
			)
		)
		(property "Description" "SMD Multilayer Ceramic Capacitor"
			(at 353.06 91.44 0)
			(effects
				(font
					(size 1.27 1.27)
				)
				(hide yes)
			)
		)
		(property "MPN" "CL10A226MO7JZNC"
			(at 370.84 71.12 0)
			(effects
				(font
					(size 1.27 1.27)
					(thickness 0.15)
				)
				(justify left bottom)
				(hide yes)
			)
		)
		(property "Manufacturer" "Samsung Electro-Mechanics"
			(at 373.38 71.12 0)
			(effects
				(font
					(size 1.27 1.27)
					(thickness 0.15)
				)
				(justify left bottom)
				(hide yes)
			)
		)
		(property "License" "Apache-2.0"
			(at 375.92 71.12 0)
			(effects
				(font
					(size 1.27 1.27)
					(thickness 0.15)
				)
				(justify left bottom)
				(hide yes)
			)
		)
		(property "Author" "Antmicro"
			(at 378.46 71.12 0)
			(effects
				(font
					(size 1.27 1.27)
					(thickness 0.15)
				)
				(justify left bottom)
				(hide yes)
			)
		)
		(property "Val" "22u"
			(at 355.6 90.1636 90)
			(effects
				(font
					(size 1.27 1.27)
					(thickness 0.15)
				)
				(justify right)
			)
		)
		(property "Voltage" "16V"
			(at 381 71.12 0)
			(effects
				(font
					(size 1.27 1.27)
				)
				(justify left bottom)
				(hide yes)
			)
		)
		(property "Dielectric" ""
			(at 383.54 71.12 0)
			(effects
				(font
					(size 1.27 1.27)
				)
				(justify left bottom)
				(hide yes)
			)
		)
		(pin "1"
		)
		(pin "2"
		)
		(instances
			(project "OCuLink to 10GbE adapter"
				(path ""
					(reference "C122")
					(unit 1)
				)
			)
		)
	)
	(symbol
		(lib_id "antmicropower:GND")
		(at 41.91 156.21 0)
		(unit 1)
		(exclude_from_sim no)
		(in_bom yes)
		(on_board yes)
		(dnp no)
		(property "Reference" "#PWR0213"
			(at 50.8 158.75 0)
			(effects
				(font
					(size 1.27 1.27)
					(thickness 0.15)
				)
				(justify left bottom)
				(hide yes)
			)
		)
		(property "Value" "GND"
			(at 41.91 160.02 0)
			(effects
				(font
					(size 1.27 1.27)
					(thickness 0.15)
				)
			)
		)
		(property "Footprint" ""
			(at 50.8 163.83 0)
			(effects
				(font
					(size 1.27 1.27)
					(thickness 0.15)
				)
				(justify left bottom)
				(hide yes)
			)
		)
		(property "Datasheet" ""
			(at 50.8 168.91 0)
			(effects
				(font
					(size 1.27 1.27)
					(thickness 0.15)
				)
				(justify left bottom)
				(hide yes)
			)
		)
		(property "Description" ""
			(at 41.91 156.21 0)
			(effects
				(font
					(size 1.27 1.27)
				)
				(hide yes)
			)
		)
		(property "Author" "Antmicro"
			(at 50.8 163.83 0)
			(effects
				(font
					(size 1.27 1.27)
					(thickness 0.15)
				)
				(justify left bottom)
				(hide yes)
			)
		)
		(property "License" "Apache-2.0"
			(at 50.8 166.37 0)
			(effects
				(font
					(size 1.27 1.27)
					(thickness 0.15)
				)
				(justify left bottom)
				(hide yes)
			)
		)
		(pin "1"
		)
		(instances
			(project "OCuLink to 10GbE adapter"
				(path ""
					(reference "#PWR0213")
					(unit 1)
				)
			)
		)
	)
	(symbol
		(lib_id "antmicropower:GND")
		(at 62.23 129.54 0)
		(unit 1)
		(exclude_from_sim no)
		(in_bom yes)
		(on_board yes)
		(dnp no)
		(property "Reference" "#PWR0189"
			(at 71.12 132.08 0)
			(effects
				(font
					(size 1.27 1.27)
					(thickness 0.15)
				)
				(justify left bottom)
				(hide yes)
			)
		)
		(property "Value" "GND"
			(at 62.23 133.35 0)
			(effects
				(font
					(size 1.27 1.27)
					(thickness 0.15)
				)
			)
		)
		(property "Footprint" ""
			(at 71.12 137.16 0)
			(effects
				(font
					(size 1.27 1.27)
					(thickness 0.15)
				)
				(justify left bottom)
				(hide yes)
			)
		)
		(property "Datasheet" ""
			(at 71.12 142.24 0)
			(effects
				(font
					(size 1.27 1.27)
					(thickness 0.15)
				)
				(justify left bottom)
				(hide yes)
			)
		)
		(property "Description" ""
			(at 62.23 129.54 0)
			(effects
				(font
					(size 1.27 1.27)
				)
				(hide yes)
			)
		)
		(property "Author" "Antmicro"
			(at 71.12 137.16 0)
			(effects
				(font
					(size 1.27 1.27)
					(thickness 0.15)
				)
				(justify left bottom)
				(hide yes)
			)
		)
		(property "License" "Apache-2.0"
			(at 71.12 139.7 0)
			(effects
				(font
					(size 1.27 1.27)
					(thickness 0.15)
				)
				(justify left bottom)
				(hide yes)
			)
		)
		(pin "1"
		)
		(instances
			(project "OCuLink to 10GbE adapter"
				(path ""
					(reference "#PWR0189")
					(unit 1)
				)
			)
		)
	)
	(symbol
		(lib_id "antmicroCapacitors0402:C_1u_25V_0402")
		(at 326.39 113.03 90)
		(unit 1)
		(exclude_from_sim no)
		(in_bom yes)
		(on_board yes)
		(dnp no)
		(property "Reference" "C132"
			(at 328.422 109.22 90)
			(effects
				(font
					(size 1.27 1.27)
					(thickness 0.15)
				)
				(justify right)
			)
		)
		(property "Value" "C_1u_25V_0402"
			(at 336.55 92.71 0)
			(effects
				(font
					(size 1.27 1.27)
					(thickness 0.15)
				)
				(justify left bottom)
				(hide yes)
			)
		)
		(property "Footprint" "antmicro-footprints:C_0402_1005Metric"
			(at 339.09 92.71 0)
			(effects
				(font
					(size 1.27 1.27)
					(thickness 0.15)
				)
				(justify left bottom)
				(hide yes)
			)
		)
		(property "Datasheet" "https://www.murata.com/products/productdetail?partno=GRM155R61E105KE11%23"
			(at 341.63 92.71 0)
			(effects
				(font
					(size 1.27 1.27)
					(thickness 0.15)
				)
				(justify left bottom)
				(hide yes)
			)
		)
		(property "Description" "SMD Multilayer Ceramic Capacitor, 1 µF, 25 V, 0402 [1005 Metric], ± 10%, X5R, GRM Series"
			(at 326.39 113.03 0)
			(effects
				(font
					(size 1.27 1.27)
				)
				(hide yes)
			)
		)
		(property "MPN" "GRM155R61E105KE11J"
			(at 344.17 92.71 0)
			(effects
				(font
					(size 1.27 1.27)
					(thickness 0.15)
				)
				(justify left bottom)
				(hide yes)
			)
		)
		(property "Manufacturer" "Murata"
			(at 346.71 92.71 0)
			(effects
				(font
					(size 1.27 1.27)
					(thickness 0.15)
				)
				(justify left bottom)
				(hide yes)
			)
		)
		(property "License" "Apache-2.0"
			(at 349.25 92.71 0)
			(effects
				(font
					(size 1.27 1.27)
					(thickness 0.15)
				)
				(justify left bottom)
				(hide yes)
			)
		)
		(property "Author" "Antmicro"
			(at 351.79 92.71 0)
			(effects
				(font
					(size 1.27 1.27)
					(thickness 0.15)
				)
				(justify left bottom)
				(hide yes)
			)
		)
		(property "Val" "1u"
			(at 328.422 111.76 90)
			(effects
				(font
					(size 1.27 1.27)
					(thickness 0.15)
				)
				(justify right)
			)
		)
		(property "Voltage" "25V"
			(at 354.33 92.71 0)
			(effects
				(font
					(size 1.27 1.27)
				)
				(justify left bottom)
				(hide yes)
			)
		)
		(property "Dielectric" "X5R"
			(at 356.87 92.71 0)
			(effects
				(font
					(size 1.27 1.27)
				)
				(justify left bottom)
				(hide yes)
			)
		)
		(pin "2"
		)
		(pin "1"
		)
		(instances
			(project "OCuLink to 10GbE adapter"
				(path ""
					(reference "C132")
					(unit 1)
				)
			)
		)
	)
	(symbol
		(lib_id "antmicroCapacitors0603:C_22u_16V_0603")
		(at 397.51 91.44 90)
		(unit 1)
		(exclude_from_sim no)
		(in_bom yes)
		(on_board yes)
		(dnp no)
		(fields_autoplaced yes)
		(property "Reference" "C127"
			(at 400.05 87.6236 90)
			(effects
				(font
					(size 1.27 1.27)
					(thickness 0.15)
				)
				(justify right)
			)
		)
		(property "Value" "C_22u_16V_0603"
			(at 407.67 71.12 0)
			(effects
				(font
					(size 1.27 1.27)
					(thickness 0.15)
				)
				(justify left bottom)
				(hide yes)
			)
		)
		(property "Footprint" "antmicro-footprints:C_0603_1608Metric_EIA"
			(at 410.21 71.12 0)
			(effects
				(font
					(size 1.27 1.27)
					(thickness 0.15)
				)
				(justify left bottom)
				(hide yes)
			)
		)
		(property "Datasheet" "https://product.samsungsem.com/mlcc/CL10A226MO7JZN.do"
			(at 412.75 71.12 0)
			(effects
				(font
					(size 1.27 1.27)
					(thickness 0.15)
				)
				(justify left bottom)
				(hide yes)
			)
		)
		(property "Description" "SMD Multilayer Ceramic Capacitor"
			(at 397.51 91.44 0)
			(effects
				(font
					(size 1.27 1.27)
				)
				(hide yes)
			)
		)
		(property "MPN" "CL10A226MO7JZNC"
			(at 415.29 71.12 0)
			(effects
				(font
					(size 1.27 1.27)
					(thickness 0.15)
				)
				(justify left bottom)
				(hide yes)
			)
		)
		(property "Manufacturer" "Samsung Electro-Mechanics"
			(at 417.83 71.12 0)
			(effects
				(font
					(size 1.27 1.27)
					(thickness 0.15)
				)
				(justify left bottom)
				(hide yes)
			)
		)
		(property "License" "Apache-2.0"
			(at 420.37 71.12 0)
			(effects
				(font
					(size 1.27 1.27)
					(thickness 0.15)
				)
				(justify left bottom)
				(hide yes)
			)
		)
		(property "Author" "Antmicro"
			(at 422.91 71.12 0)
			(effects
				(font
					(size 1.27 1.27)
					(thickness 0.15)
				)
				(justify left bottom)
				(hide yes)
			)
		)
		(property "Val" "22u"
			(at 400.05 90.1636 90)
			(effects
				(font
					(size 1.27 1.27)
					(thickness 0.15)
				)
				(justify right)
			)
		)
		(property "Voltage" "16V"
			(at 425.45 71.12 0)
			(effects
				(font
					(size 1.27 1.27)
				)
				(justify left bottom)
				(hide yes)
			)
		)
		(property "Dielectric" ""
			(at 427.99 71.12 0)
			(effects
				(font
					(size 1.27 1.27)
				)
				(justify left bottom)
				(hide yes)
			)
		)
		(pin "1"
		)
		(pin "2"
		)
		(instances
			(project ""
				(path ""
					(reference "C127")
					(unit 1)
				)
			)
		)
	)
	(symbol
		(lib_id "antmicropower:GND")
		(at 106.68 182.88 0)
		(unit 1)
		(exclude_from_sim no)
		(in_bom yes)
		(on_board yes)
		(dnp no)
		(property "Reference" "#PWR0229"
			(at 115.57 185.42 0)
			(effects
				(font
					(size 1.27 1.27)
					(thickness 0.15)
				)
				(justify left bottom)
				(hide yes)
			)
		)
		(property "Value" "GND"
			(at 106.68 186.69 0)
			(effects
				(font
					(size 1.27 1.27)
					(thickness 0.15)
				)
			)
		)
		(property "Footprint" ""
			(at 115.57 190.5 0)
			(effects
				(font
					(size 1.27 1.27)
					(thickness 0.15)
				)
				(justify left bottom)
				(hide yes)
			)
		)
		(property "Datasheet" ""
			(at 115.57 195.58 0)
			(effects
				(font
					(size 1.27 1.27)
					(thickness 0.15)
				)
				(justify left bottom)
				(hide yes)
			)
		)
		(property "Description" ""
			(at 106.68 182.88 0)
			(effects
				(font
					(size 1.27 1.27)
				)
				(hide yes)
			)
		)
		(property "Author" "Antmicro"
			(at 115.57 190.5 0)
			(effects
				(font
					(size 1.27 1.27)
					(thickness 0.15)
				)
				(justify left bottom)
				(hide yes)
			)
		)
		(property "License" "Apache-2.0"
			(at 115.57 193.04 0)
			(effects
				(font
					(size 1.27 1.27)
					(thickness 0.15)
				)
				(justify left bottom)
				(hide yes)
			)
		)
		(pin "1"
		)
		(instances
			(project "OCuLink to 10GbE adapter"
				(path ""
					(reference "#PWR0229")
					(unit 1)
				)
			)
		)
	)
	(symbol
		(lib_id "antmicroCapacitors0603:C_10u_10V_X7R_0603")
		(at 71.12 180.34 90)
		(unit 1)
		(exclude_from_sim no)
		(in_bom yes)
		(on_board yes)
		(dnp no)
		(property "Reference" "C174"
			(at 72.898 176.53 90)
			(effects
				(font
					(size 1.27 1.27)
					(thickness 0.15)
				)
				(justify right)
			)
		)
		(property "Value" "C_10u_10V_X7R_0603"
			(at 81.28 165.1 0)
			(effects
				(font
					(size 1.27 1.27)
					(thickness 0.15)
				)
				(justify left bottom)
				(hide yes)
			)
		)
		(property "Footprint" "antmicro-footprints:C_0603_1608Metric"
			(at 83.82 165.1 0)
			(effects
				(font
					(size 1.27 1.27)
					(thickness 0.15)
				)
				(justify left bottom)
				(hide yes)
			)
		)
		(property "Datasheet" "https://www.murata.com/products/productdetail?partno=GRM188Z71A106KA73%23"
			(at 86.36 165.1 0)
			(effects
				(font
					(size 1.27 1.27)
					(thickness 0.15)
				)
				(justify left bottom)
				(hide yes)
			)
		)
		(property "Description" "SMD Multilayer Ceramic Capacitor,  10µF, 10V, 0603, ±10%, X7R"
			(at 71.12 180.34 0)
			(effects
				(font
					(size 1.27 1.27)
				)
				(hide yes)
			)
		)
		(property "MPN" "GRM188Z71A106KA73D"
			(at 88.9 165.1 0)
			(effects
				(font
					(size 1.27 1.27)
					(thickness 0.15)
				)
				(justify left bottom)
				(hide yes)
			)
		)
		(property "Val" "10u"
			(at 72.898 179.07 90)
			(effects
				(font
					(size 1.27 1.27)
					(thickness 0.15)
				)
				(justify right)
			)
		)
		(property "Voltage" "10V"
			(at 91.44 165.1 0)
			(effects
				(font
					(size 1.27 1.27)
					(thickness 0.15)
				)
				(justify left bottom)
				(hide yes)
			)
		)
		(property "Dielectric" "X7R"
			(at 93.98 165.1 0)
			(effects
				(font
					(size 1.27 1.27)
					(thickness 0.15)
				)
				(justify left bottom)
				(hide yes)
			)
		)
		(property "Manufacturer" "Murata"
			(at 96.52 165.1 0)
			(effects
				(font
					(size 1.27 1.27)
					(thickness 0.15)
				)
				(justify left bottom)
				(hide yes)
			)
		)
		(property "License" "Apache-2.0"
			(at 99.06 165.1 0)
			(effects
				(font
					(size 1.27 1.27)
					(thickness 0.15)
				)
				(justify left bottom)
				(hide yes)
			)
		)
		(property "Author" "Antmicro"
			(at 101.6 165.1 0)
			(effects
				(font
					(size 1.27 1.27)
					(thickness 0.15)
				)
				(justify left bottom)
				(hide yes)
			)
		)
		(pin "1"
		)
		(pin "2"
		)
		(instances
			(project "OCuLink to 10GbE adapter"
				(path ""
					(reference "C174")
					(unit 1)
				)
			)
		)
	)
	(symbol
		(lib_id "antmicropower:PWR_FLAG")
		(at 66.04 144.78 0)
		(unit 1)
		(exclude_from_sim no)
		(in_bom yes)
		(on_board yes)
		(dnp no)
		(fields_autoplaced yes)
		(property "Reference" "#FLG015"
			(at 66.04 142.875 0)
			(effects
				(font
					(size 1.27 1.27)
				)
				(hide yes)
			)
		)
		(property "Value" "PWR_FLAG"
			(at 66.04 139.7 0)
			(effects
				(font
					(size 1.27 1.27)
				)
			)
		)
		(property "Footprint" ""
			(at 66.04 144.78 0)
			(effects
				(font
					(size 1.27 1.27)
				)
				(hide yes)
			)
		)
		(property "Datasheet" ""
			(at 66.04 144.78 0)
			(effects
				(font
					(size 1.27 1.27)
				)
				(hide yes)
			)
		)
		(property "Description" ""
			(at 66.04 147.32 0)
			(effects
				(font
					(size 1.27 1.27)
				)
				(justify left bottom)
				(hide yes)
			)
		)
		(pin "1"
		)
		(instances
			(project "OCuLink to 10GbE adapter"
				(path ""
					(reference "#FLG015")
					(unit 1)
				)
			)
		)
	)
	(symbol
		(lib_id "antmicropower:GND")
		(at 397.51 76.2 0)
		(unit 1)
		(exclude_from_sim no)
		(in_bom yes)
		(on_board yes)
		(dnp no)
		(property "Reference" "#PWR0150"
			(at 406.4 78.74 0)
			(effects
				(font
					(size 1.27 1.27)
					(thickness 0.15)
				)
				(justify left bottom)
				(hide yes)
			)
		)
		(property "Value" "GND"
			(at 397.51 80.01 0)
			(effects
				(font
					(size 1.27 1.27)
					(thickness 0.15)
				)
			)
		)
		(property "Footprint" ""
			(at 406.4 83.82 0)
			(effects
				(font
					(size 1.27 1.27)
					(thickness 0.15)
				)
				(justify left bottom)
				(hide yes)
			)
		)
		(property "Datasheet" ""
			(at 406.4 88.9 0)
			(effects
				(font
					(size 1.27 1.27)
					(thickness 0.15)
				)
				(justify left bottom)
				(hide yes)
			)
		)
		(property "Description" ""
			(at 397.51 76.2 0)
			(effects
				(font
					(size 1.27 1.27)
				)
				(hide yes)
			)
		)
		(property "Author" "Antmicro"
			(at 406.4 83.82 0)
			(effects
				(font
					(size 1.27 1.27)
					(thickness 0.15)
				)
				(justify left bottom)
				(hide yes)
			)
		)
		(property "License" "Apache-2.0"
			(at 406.4 86.36 0)
			(effects
				(font
					(size 1.27 1.27)
					(thickness 0.15)
				)
				(justify left bottom)
				(hide yes)
			)
		)
		(pin "1"
		)
		(instances
			(project "OCuLink to 10GbE adapter"
				(path ""
					(reference "#PWR0150")
					(unit 1)
				)
			)
		)
	)
	(symbol
		(lib_id "antmicroCapacitors0402:C_1u_25V_0402")
		(at 53.34 100.33 90)
		(unit 1)
		(exclude_from_sim no)
		(in_bom yes)
		(on_board yes)
		(dnp no)
		(property "Reference" "C129"
			(at 55.372 96.52 90)
			(effects
				(font
					(size 1.27 1.27)
					(thickness 0.15)
				)
				(justify right)
			)
		)
		(property "Value" "C_1u_25V_0402"
			(at 63.5 80.01 0)
			(effects
				(font
					(size 1.27 1.27)
					(thickness 0.15)
				)
				(justify left bottom)
				(hide yes)
			)
		)
		(property "Footprint" "antmicro-footprints:C_0402_1005Metric"
			(at 66.04 80.01 0)
			(effects
				(font
					(size 1.27 1.27)
					(thickness 0.15)
				)
				(justify left bottom)
				(hide yes)
			)
		)
		(property "Datasheet" "https://www.murata.com/products/productdetail?partno=GRM155R61E105KE11%23"
			(at 68.58 80.01 0)
			(effects
				(font
					(size 1.27 1.27)
					(thickness 0.15)
				)
				(justify left bottom)
				(hide yes)
			)
		)
		(property "Description" "SMD Multilayer Ceramic Capacitor, 1 µF, 25 V, 0402 [1005 Metric], ± 10%, X5R, GRM Series"
			(at 53.34 100.33 0)
			(effects
				(font
					(size 1.27 1.27)
				)
				(hide yes)
			)
		)
		(property "MPN" "GRM155R61E105KE11J"
			(at 71.12 80.01 0)
			(effects
				(font
					(size 1.27 1.27)
					(thickness 0.15)
				)
				(justify left bottom)
				(hide yes)
			)
		)
		(property "Manufacturer" "Murata"
			(at 73.66 80.01 0)
			(effects
				(font
					(size 1.27 1.27)
					(thickness 0.15)
				)
				(justify left bottom)
				(hide yes)
			)
		)
		(property "License" "Apache-2.0"
			(at 76.2 80.01 0)
			(effects
				(font
					(size 1.27 1.27)
					(thickness 0.15)
				)
				(justify left bottom)
				(hide yes)
			)
		)
		(property "Author" "Antmicro"
			(at 78.74 80.01 0)
			(effects
				(font
					(size 1.27 1.27)
					(thickness 0.15)
				)
				(justify left bottom)
				(hide yes)
			)
		)
		(property "Val" "1u"
			(at 55.372 99.06 90)
			(effects
				(font
					(size 1.27 1.27)
					(thickness 0.15)
				)
				(justify right)
			)
		)
		(property "Voltage" "25V"
			(at 81.28 80.01 0)
			(effects
				(font
					(size 1.27 1.27)
				)
				(justify left bottom)
				(hide yes)
			)
		)
		(property "Dielectric" "X5R"
			(at 83.82 80.01 0)
			(effects
				(font
					(size 1.27 1.27)
				)
				(justify left bottom)
				(hide yes)
			)
		)
		(pin "2"
		)
		(pin "1"
		)
		(instances
			(project "OCuLink to 10GbE adapter"
				(path ""
					(reference "C129")
					(unit 1)
				)
			)
		)
	)
	(symbol
		(lib_id "antmicroCapacitors0402:C_1u_25V_0402")
		(at 344.17 52.07 90)
		(unit 1)
		(exclude_from_sim no)
		(in_bom yes)
		(on_board yes)
		(dnp no)
		(property "Reference" "C92"
			(at 346.202 48.26 90)
			(effects
				(font
					(size 1.27 1.27)
					(thickness 0.15)
				)
				(justify right)
			)
		)
		(property "Value" "C_1u_25V_0402"
			(at 354.33 31.75 0)
			(effects
				(font
					(size 1.27 1.27)
					(thickness 0.15)
				)
				(justify left bottom)
				(hide yes)
			)
		)
		(property "Footprint" "antmicro-footprints:C_0402_1005Metric"
			(at 356.87 31.75 0)
			(effects
				(font
					(size 1.27 1.27)
					(thickness 0.15)
				)
				(justify left bottom)
				(hide yes)
			)
		)
		(property "Datasheet" "https://www.murata.com/products/productdetail?partno=GRM155R61E105KE11%23"
			(at 359.41 31.75 0)
			(effects
				(font
					(size 1.27 1.27)
					(thickness 0.15)
				)
				(justify left bottom)
				(hide yes)
			)
		)
		(property "Description" "SMD Multilayer Ceramic Capacitor, 1 µF, 25 V, 0402 [1005 Metric], ± 10%, X5R, GRM Series"
			(at 344.17 52.07 0)
			(effects
				(font
					(size 1.27 1.27)
				)
				(hide yes)
			)
		)
		(property "MPN" "GRM155R61E105KE11J"
			(at 361.95 31.75 0)
			(effects
				(font
					(size 1.27 1.27)
					(thickness 0.15)
				)
				(justify left bottom)
				(hide yes)
			)
		)
		(property "Manufacturer" "Murata"
			(at 364.49 31.75 0)
			(effects
				(font
					(size 1.27 1.27)
					(thickness 0.15)
				)
				(justify left bottom)
				(hide yes)
			)
		)
		(property "License" "Apache-2.0"
			(at 367.03 31.75 0)
			(effects
				(font
					(size 1.27 1.27)
					(thickness 0.15)
				)
				(justify left bottom)
				(hide yes)
			)
		)
		(property "Author" "Antmicro"
			(at 369.57 31.75 0)
			(effects
				(font
					(size 1.27 1.27)
					(thickness 0.15)
				)
				(justify left bottom)
				(hide yes)
			)
		)
		(property "Val" "1u"
			(at 346.202 50.8 90)
			(effects
				(font
					(size 1.27 1.27)
					(thickness 0.15)
				)
				(justify right)
			)
		)
		(property "Voltage" "25V"
			(at 372.11 31.75 0)
			(effects
				(font
					(size 1.27 1.27)
				)
				(justify left bottom)
				(hide yes)
			)
		)
		(property "Dielectric" "X5R"
			(at 374.65 31.75 0)
			(effects
				(font
					(size 1.27 1.27)
				)
				(justify left bottom)
				(hide yes)
			)
		)
		(pin "2"
		)
		(pin "1"
		)
		(instances
			(project "OCuLink to 10GbE adapter"
				(path ""
					(reference "C92")
					(unit 1)
				)
			)
		)
	)
	(symbol
		(lib_id "antmicropower:GND")
		(at 326.39 76.2 0)
		(unit 1)
		(exclude_from_sim no)
		(in_bom yes)
		(on_board yes)
		(dnp no)
		(property "Reference" "#PWR0142"
			(at 335.28 78.74 0)
			(effects
				(font
					(size 1.27 1.27)
					(thickness 0.15)
				)
				(justify left bottom)
				(hide yes)
			)
		)
		(property "Value" "GND"
			(at 326.39 80.01 0)
			(effects
				(font
					(size 1.27 1.27)
					(thickness 0.15)
				)
			)
		)
		(property "Footprint" ""
			(at 335.28 83.82 0)
			(effects
				(font
					(size 1.27 1.27)
					(thickness 0.15)
				)
				(justify left bottom)
				(hide yes)
			)
		)
		(property "Datasheet" ""
			(at 335.28 88.9 0)
			(effects
				(font
					(size 1.27 1.27)
					(thickness 0.15)
				)
				(justify left bottom)
				(hide yes)
			)
		)
		(property "Description" ""
			(at 326.39 76.2 0)
			(effects
				(font
					(size 1.27 1.27)
				)
				(hide yes)
			)
		)
		(property "Author" "Antmicro"
			(at 335.28 83.82 0)
			(effects
				(font
					(size 1.27 1.27)
					(thickness 0.15)
				)
				(justify left bottom)
				(hide yes)
			)
		)
		(property "License" "Apache-2.0"
			(at 335.28 86.36 0)
			(effects
				(font
					(size 1.27 1.27)
					(thickness 0.15)
				)
				(justify left bottom)
				(hide yes)
			)
		)
		(pin "1"
		)
		(instances
			(project "OCuLink to 10GbE adapter"
				(path ""
					(reference "#PWR0142")
					(unit 1)
				)
			)
		)
	)
	(symbol
		(lib_id "antmicroFerriteBeadsandChips:FB_33Z_3A_Murata-BLM18PG_0603")
		(at 45.72 146.05 0)
		(unit 1)
		(exclude_from_sim no)
		(in_bom yes)
		(on_board yes)
		(dnp no)
		(fields_autoplaced yes)
		(property "Reference" "FB5"
			(at 48.2219 139.7 0)
			(effects
				(font
					(size 1.27 1.27)
					(thickness 0.15)
				)
			)
		)
		(property "Value" "FB_33Z_3A_Murata-BLM18PG_0603"
			(at 59.69 148.59 0)
			(effects
				(font
					(size 1.27 1.27)
					(thickness 0.15)
				)
				(justify left bottom)
				(hide yes)
			)
		)
		(property "Footprint" "antmicro-footprints:FB_0603_1608Metric"
			(at 59.69 153.67 0)
			(effects
				(font
					(size 1.27 1.27)
					(thickness 0.15)
				)
				(justify left bottom)
				(hide yes)
			)
		)
		(property "Datasheet" "https://www.murata.com/products/productdata/8796737273886/QNFA9101.pdf?1649080818000"
			(at 59.69 156.21 0)
			(effects
				(font
					(size 1.27 1.27)
					(thickness 0.15)
				)
				(justify left bottom)
				(hide yes)
			)
		)
		(property "Description" "Ferrite Bead, 0603 [1608 Metric], 33 ohm, 3 A, BLM18PG, 0.025 ohm, ± 25%, DC power line"
			(at 45.72 146.05 0)
			(effects
				(font
					(size 1.27 1.27)
				)
				(hide yes)
			)
		)
		(property "Val" "33Z/3A"
			(at 48.2219 142.24 0)
			(effects
				(font
					(size 1.27 1.27)
				)
			)
		)
		(property "MPN" "BLM18PG330SH1D"
			(at 59.69 158.75 0)
			(effects
				(font
					(size 1.27 1.27)
					(thickness 0.15)
				)
				(justify left bottom)
				(hide yes)
			)
		)
		(property "Manufacturer" "Murata"
			(at 59.69 161.29 0)
			(effects
				(font
					(size 1.27 1.27)
					(thickness 0.15)
				)
				(justify left bottom)
				(hide yes)
			)
		)
		(property "Current" ""
			(at 66.04 168.91 0)
			(effects
				(font
					(size 1.27 1.27)
					(thickness 0.15)
				)
				(justify left bottom)
				(hide yes)
			)
		)
		(property "Author" "Antmicro"
			(at 59.69 163.83 0)
			(effects
				(font
					(size 1.27 1.27)
					(thickness 0.15)
				)
				(justify left bottom)
				(hide yes)
			)
		)
		(property "License" "Apache-2.0"
			(at 59.69 166.37 0)
			(effects
				(font
					(size 1.27 1.27)
					(thickness 0.15)
				)
				(justify left bottom)
				(hide yes)
			)
		)
		(pin "2"
		)
		(pin "1"
		)
		(instances
			(project "OCuLink to 10GbE adapter"
				(path ""
					(reference "FB5")
					(unit 1)
				)
			)
		)
	)
	(symbol
		(lib_id "antmicropower:GND")
		(at 97.79 156.21 0)
		(unit 1)
		(exclude_from_sim no)
		(in_bom yes)
		(on_board yes)
		(dnp no)
		(property "Reference" "#PWR0218"
			(at 106.68 158.75 0)
			(effects
				(font
					(size 1.27 1.27)
					(thickness 0.15)
				)
				(justify left bottom)
				(hide yes)
			)
		)
		(property "Value" "GND"
			(at 97.79 160.02 0)
			(effects
				(font
					(size 1.27 1.27)
					(thickness 0.15)
				)
			)
		)
		(property "Footprint" ""
			(at 106.68 163.83 0)
			(effects
				(font
					(size 1.27 1.27)
					(thickness 0.15)
				)
				(justify left bottom)
				(hide yes)
			)
		)
		(property "Datasheet" ""
			(at 106.68 168.91 0)
			(effects
				(font
					(size 1.27 1.27)
					(thickness 0.15)
				)
				(justify left bottom)
				(hide yes)
			)
		)
		(property "Description" ""
			(at 97.79 156.21 0)
			(effects
				(font
					(size 1.27 1.27)
				)
				(hide yes)
			)
		)
		(property "Author" "Antmicro"
			(at 106.68 163.83 0)
			(effects
				(font
					(size 1.27 1.27)
					(thickness 0.15)
				)
				(justify left bottom)
				(hide yes)
			)
		)
		(property "License" "Apache-2.0"
			(at 106.68 166.37 0)
			(effects
				(font
					(size 1.27 1.27)
					(thickness 0.15)
				)
				(justify left bottom)
				(hide yes)
			)
		)
		(pin "1"
		)
		(instances
			(project "OCuLink to 10GbE adapter"
				(path ""
					(reference "#PWR0218")
					(unit 1)
				)
			)
		)
	)
	(symbol
		(lib_id "antmicropower:GND")
		(at 115.57 156.21 0)
		(unit 1)
		(exclude_from_sim no)
		(in_bom yes)
		(on_board yes)
		(dnp no)
		(property "Reference" "#PWR0220"
			(at 124.46 158.75 0)
			(effects
				(font
					(size 1.27 1.27)
					(thickness 0.15)
				)
				(justify left bottom)
				(hide yes)
			)
		)
		(property "Value" "GND"
			(at 115.57 160.02 0)
			(effects
				(font
					(size 1.27 1.27)
					(thickness 0.15)
				)
			)
		)
		(property "Footprint" ""
			(at 124.46 163.83 0)
			(effects
				(font
					(size 1.27 1.27)
					(thickness 0.15)
				)
				(justify left bottom)
				(hide yes)
			)
		)
		(property "Datasheet" ""
			(at 124.46 168.91 0)
			(effects
				(font
					(size 1.27 1.27)
					(thickness 0.15)
				)
				(justify left bottom)
				(hide yes)
			)
		)
		(property "Description" ""
			(at 115.57 156.21 0)
			(effects
				(font
					(size 1.27 1.27)
				)
				(hide yes)
			)
		)
		(property "Author" "Antmicro"
			(at 124.46 163.83 0)
			(effects
				(font
					(size 1.27 1.27)
					(thickness 0.15)
				)
				(justify left bottom)
				(hide yes)
			)
		)
		(property "License" "Apache-2.0"
			(at 124.46 166.37 0)
			(effects
				(font
					(size 1.27 1.27)
					(thickness 0.15)
				)
				(justify left bottom)
				(hide yes)
			)
		)
		(pin "1"
		)
		(instances
			(project "OCuLink to 10GbE adapter"
				(path ""
					(reference "#PWR0220")
					(unit 1)
				)
			)
		)
	)
	(symbol
		(lib_id "antmicropower:GND")
		(at 299.72 115.57 0)
		(unit 1)
		(exclude_from_sim no)
		(in_bom yes)
		(on_board yes)
		(dnp no)
		(property "Reference" "#PWR0178"
			(at 308.61 118.11 0)
			(effects
				(font
					(size 1.27 1.27)
					(thickness 0.15)
				)
				(justify left bottom)
				(hide yes)
			)
		)
		(property "Value" "GND"
			(at 299.72 119.38 0)
			(effects
				(font
					(size 1.27 1.27)
					(thickness 0.15)
				)
			)
		)
		(property "Footprint" ""
			(at 308.61 123.19 0)
			(effects
				(font
					(size 1.27 1.27)
					(thickness 0.15)
				)
				(justify left bottom)
				(hide yes)
			)
		)
		(property "Datasheet" ""
			(at 308.61 128.27 0)
			(effects
				(font
					(size 1.27 1.27)
					(thickness 0.15)
				)
				(justify left bottom)
				(hide yes)
			)
		)
		(property "Description" ""
			(at 299.72 115.57 0)
			(effects
				(font
					(size 1.27 1.27)
				)
				(hide yes)
			)
		)
		(property "Author" "Antmicro"
			(at 308.61 123.19 0)
			(effects
				(font
					(size 1.27 1.27)
					(thickness 0.15)
				)
				(justify left bottom)
				(hide yes)
			)
		)
		(property "License" "Apache-2.0"
			(at 308.61 125.73 0)
			(effects
				(font
					(size 1.27 1.27)
					(thickness 0.15)
				)
				(justify left bottom)
				(hide yes)
			)
		)
		(pin "1"
		)
		(instances
			(project "OCuLink to 10GbE adapter"
				(path ""
					(reference "#PWR0178")
					(unit 1)
				)
			)
		)
	)
	(symbol
		(lib_id "antmicropower:VDD")
		(at 135.89 78.74 0)
		(unit 1)
		(exclude_from_sim no)
		(in_bom yes)
		(on_board yes)
		(dnp no)
		(property "Reference" "#PWR0151"
			(at 135.89 82.55 0)
			(effects
				(font
					(size 1.27 1.27)
				)
				(hide yes)
			)
		)
		(property "Value" "PLL_VDD"
			(at 135.89 74.93 0)
			(effects
				(font
					(size 1.27 1.27)
				)
			)
		)
		(property "Footprint" ""
			(at 135.89 78.74 0)
			(effects
				(font
					(size 1.27 1.27)
				)
				(hide yes)
			)
		)
		(property "Datasheet" ""
			(at 135.89 78.74 0)
			(effects
				(font
					(size 1.27 1.27)
				)
				(hide yes)
			)
		)
		(property "Description" ""
			(at 135.89 78.74 0)
			(effects
				(font
					(size 1.27 1.27)
				)
				(hide yes)
			)
		)
		(pin "1"
		)
		(instances
			(project "OCuLink to 10GbE adapter"
				(path ""
					(reference "#PWR0151")
					(unit 1)
				)
			)
		)
	)
	(symbol
		(lib_id "antmicropower:GND")
		(at 62.23 182.88 0)
		(unit 1)
		(exclude_from_sim no)
		(in_bom yes)
		(on_board yes)
		(dnp no)
		(property "Reference" "#PWR0225"
			(at 71.12 185.42 0)
			(effects
				(font
					(size 1.27 1.27)
					(thickness 0.15)
				)
				(justify left bottom)
				(hide yes)
			)
		)
		(property "Value" "GND"
			(at 62.23 186.69 0)
			(effects
				(font
					(size 1.27 1.27)
					(thickness 0.15)
				)
			)
		)
		(property "Footprint" ""
			(at 71.12 190.5 0)
			(effects
				(font
					(size 1.27 1.27)
					(thickness 0.15)
				)
				(justify left bottom)
				(hide yes)
			)
		)
		(property "Datasheet" ""
			(at 71.12 195.58 0)
			(effects
				(font
					(size 1.27 1.27)
					(thickness 0.15)
				)
				(justify left bottom)
				(hide yes)
			)
		)
		(property "Description" ""
			(at 62.23 182.88 0)
			(effects
				(font
					(size 1.27 1.27)
				)
				(hide yes)
			)
		)
		(property "Author" "Antmicro"
			(at 71.12 190.5 0)
			(effects
				(font
					(size 1.27 1.27)
					(thickness 0.15)
				)
				(justify left bottom)
				(hide yes)
			)
		)
		(property "License" "Apache-2.0"
			(at 71.12 193.04 0)
			(effects
				(font
					(size 1.27 1.27)
					(thickness 0.15)
				)
				(justify left bottom)
				(hide yes)
			)
		)
		(pin "1"
		)
		(instances
			(project "OCuLink to 10GbE adapter"
				(path ""
					(reference "#PWR0225")
					(unit 1)
				)
			)
		)
	)
	(symbol
		(lib_id "antmicroCapacitors0402:C_100n_0402")
		(at 299.72 113.03 90)
		(unit 1)
		(exclude_from_sim no)
		(in_bom yes)
		(on_board yes)
		(dnp no)
		(property "Reference" "C130"
			(at 301.752 109.22 90)
			(effects
				(font
					(size 1.27 1.27)
					(thickness 0.15)
				)
				(justify right)
			)
		)
		(property "Value" "C_100n_0402"
			(at 322.58 97.79 0)
			(effects
				(font
					(size 1.27 1.27)
					(thickness 0.15)
				)
				(justify left bottom)
				(hide yes)
			)
		)
		(property "Footprint" "antmicro-footprints:C_0402_1005Metric"
			(at 325.12 97.79 0)
			(effects
				(font
					(size 1.27 1.27)
					(thickness 0.15)
				)
				(justify left bottom)
				(hide yes)
			)
		)
		(property "Datasheet" "https://www.murata.com/products/productdetail?partno=GRM155R61H104KE14%23"
			(at 327.66 97.79 0)
			(effects
				(font
					(size 1.27 1.27)
					(thickness 0.15)
				)
				(justify left bottom)
				(hide yes)
			)
		)
		(property "Description" "SMD Multilayer Ceramic Capacitor, 0.1 µF, 50 V, 0402 [1005 Metric], ± 10%, X5R, GRM Series"
			(at 299.72 113.03 0)
			(effects
				(font
					(size 1.27 1.27)
				)
				(hide yes)
			)
		)
		(property "MPN" "GRM155R61H104KE14D"
			(at 330.2 97.79 0)
			(effects
				(font
					(size 1.27 1.27)
					(thickness 0.15)
				)
				(justify left bottom)
				(hide yes)
			)
		)
		(property "Val" "100n"
			(at 301.752 111.76 90)
			(effects
				(font
					(size 1.27 1.27)
					(thickness 0.15)
				)
				(justify right)
			)
		)
		(property "Voltage" "50V"
			(at 309.88 97.79 0)
			(effects
				(font
					(size 1.27 1.27)
					(thickness 0.15)
				)
				(justify left bottom)
				(hide yes)
			)
		)
		(property "Dielectric" "X5R"
			(at 312.42 97.79 0)
			(effects
				(font
					(size 1.27 1.27)
					(thickness 0.15)
				)
				(justify left bottom)
				(hide yes)
			)
		)
		(property "Manufacturer" "Murata"
			(at 314.96 97.79 0)
			(effects
				(font
					(size 1.27 1.27)
					(thickness 0.15)
				)
				(justify left bottom)
				(hide yes)
			)
		)
		(property "License" "Apache-2.0"
			(at 317.5 97.79 0)
			(effects
				(font
					(size 1.27 1.27)
					(thickness 0.15)
				)
				(justify left bottom)
				(hide yes)
			)
		)
		(property "Author" "Antmicro"
			(at 320.04 97.79 0)
			(effects
				(font
					(size 1.27 1.27)
					(thickness 0.15)
				)
				(justify left bottom)
				(hide yes)
			)
		)
		(pin "1"
		)
		(pin "2"
		)
		(instances
			(project ""
				(path ""
					(reference "C130")
					(unit 1)
				)
			)
		)
	)
	(symbol
		(lib_id "antmicroCapacitors0402:C_1u_25V_0402")
		(at 97.79 180.34 90)
		(unit 1)
		(exclude_from_sim no)
		(in_bom yes)
		(on_board yes)
		(dnp no)
		(property "Reference" "C176"
			(at 99.822 176.53 90)
			(effects
				(font
					(size 1.27 1.27)
					(thickness 0.15)
				)
				(justify right)
			)
		)
		(property "Value" "C_1u_25V_0402"
			(at 107.95 160.02 0)
			(effects
				(font
					(size 1.27 1.27)
					(thickness 0.15)
				)
				(justify left bottom)
				(hide yes)
			)
		)
		(property "Footprint" "antmicro-footprints:C_0402_1005Metric"
			(at 110.49 160.02 0)
			(effects
				(font
					(size 1.27 1.27)
					(thickness 0.15)
				)
				(justify left bottom)
				(hide yes)
			)
		)
		(property "Datasheet" "https://www.murata.com/products/productdetail?partno=GRM155R61E105KE11%23"
			(at 113.03 160.02 0)
			(effects
				(font
					(size 1.27 1.27)
					(thickness 0.15)
				)
				(justify left bottom)
				(hide yes)
			)
		)
		(property "Description" "SMD Multilayer Ceramic Capacitor, 1 µF, 25 V, 0402 [1005 Metric], ± 10%, X5R, GRM Series"
			(at 97.79 180.34 0)
			(effects
				(font
					(size 1.27 1.27)
				)
				(hide yes)
			)
		)
		(property "MPN" "GRM155R61E105KE11J"
			(at 115.57 160.02 0)
			(effects
				(font
					(size 1.27 1.27)
					(thickness 0.15)
				)
				(justify left bottom)
				(hide yes)
			)
		)
		(property "Manufacturer" "Murata"
			(at 118.11 160.02 0)
			(effects
				(font
					(size 1.27 1.27)
					(thickness 0.15)
				)
				(justify left bottom)
				(hide yes)
			)
		)
		(property "License" "Apache-2.0"
			(at 120.65 160.02 0)
			(effects
				(font
					(size 1.27 1.27)
					(thickness 0.15)
				)
				(justify left bottom)
				(hide yes)
			)
		)
		(property "Author" "Antmicro"
			(at 123.19 160.02 0)
			(effects
				(font
					(size 1.27 1.27)
					(thickness 0.15)
				)
				(justify left bottom)
				(hide yes)
			)
		)
		(property "Val" "1u"
			(at 99.822 179.07 90)
			(effects
				(font
					(size 1.27 1.27)
					(thickness 0.15)
				)
				(justify right)
			)
		)
		(property "Voltage" "25V"
			(at 125.73 160.02 0)
			(effects
				(font
					(size 1.27 1.27)
				)
				(justify left bottom)
				(hide yes)
			)
		)
		(property "Dielectric" "X5R"
			(at 128.27 160.02 0)
			(effects
				(font
					(size 1.27 1.27)
				)
				(justify left bottom)
				(hide yes)
			)
		)
		(pin "2"
		)
		(pin "1"
		)
		(instances
			(project "OCuLink to 10GbE adapter"
				(path ""
					(reference "C176")
					(unit 1)
				)
			)
		)
	)
	(symbol
		(lib_id "antmicropower:GND")
		(at 326.39 133.35 0)
		(unit 1)
		(exclude_from_sim no)
		(in_bom yes)
		(on_board yes)
		(dnp no)
		(property "Reference" "#PWR0198"
			(at 335.28 135.89 0)
			(effects
				(font
					(size 1.27 1.27)
					(thickness 0.15)
				)
				(justify left bottom)
				(hide yes)
			)
		)
		(property "Value" "GND"
			(at 326.39 137.16 0)
			(effects
				(font
					(size 1.27 1.27)
					(thickness 0.15)
				)
			)
		)
		(property "Footprint" ""
			(at 335.28 140.97 0)
			(effects
				(font
					(size 1.27 1.27)
					(thickness 0.15)
				)
				(justify left bottom)
				(hide yes)
			)
		)
		(property "Datasheet" ""
			(at 335.28 146.05 0)
			(effects
				(font
					(size 1.27 1.27)
					(thickness 0.15)
				)
				(justify left bottom)
				(hide yes)
			)
		)
		(property "Description" ""
			(at 326.39 133.35 0)
			(effects
				(font
					(size 1.27 1.27)
				)
				(hide yes)
			)
		)
		(property "Author" "Antmicro"
			(at 335.28 140.97 0)
			(effects
				(font
					(size 1.27 1.27)
					(thickness 0.15)
				)
				(justify left bottom)
				(hide yes)
			)
		)
		(property "License" "Apache-2.0"
			(at 335.28 143.51 0)
			(effects
				(font
					(size 1.27 1.27)
					(thickness 0.15)
				)
				(justify left bottom)
				(hide yes)
			)
		)
		(pin "1"
		)
		(instances
			(project "OCuLink to 10GbE adapter"
				(path ""
					(reference "#PWR0198")
					(unit 1)
				)
			)
		)
	)
	(symbol
		(lib_id "antmicropower:GND")
		(at 88.9 156.21 0)
		(unit 1)
		(exclude_from_sim no)
		(in_bom yes)
		(on_board yes)
		(dnp no)
		(property "Reference" "#PWR0217"
			(at 97.79 158.75 0)
			(effects
				(font
					(size 1.27 1.27)
					(thickness 0.15)
				)
				(justify left bottom)
				(hide yes)
			)
		)
		(property "Value" "GND"
			(at 88.9 160.02 0)
			(effects
				(font
					(size 1.27 1.27)
					(thickness 0.15)
				)
			)
		)
		(property "Footprint" ""
			(at 97.79 163.83 0)
			(effects
				(font
					(size 1.27 1.27)
					(thickness 0.15)
				)
				(justify left bottom)
				(hide yes)
			)
		)
		(property "Datasheet" ""
			(at 97.79 168.91 0)
			(effects
				(font
					(size 1.27 1.27)
					(thickness 0.15)
				)
				(justify left bottom)
				(hide yes)
			)
		)
		(property "Description" ""
			(at 88.9 156.21 0)
			(effects
				(font
					(size 1.27 1.27)
				)
				(hide yes)
			)
		)
		(property "Author" "Antmicro"
			(at 97.79 163.83 0)
			(effects
				(font
					(size 1.27 1.27)
					(thickness 0.15)
				)
				(justify left bottom)
				(hide yes)
			)
		)
		(property "License" "Apache-2.0"
			(at 97.79 166.37 0)
			(effects
				(font
					(size 1.27 1.27)
					(thickness 0.15)
				)
				(justify left bottom)
				(hide yes)
			)
		)
		(pin "1"
		)
		(instances
			(project "OCuLink to 10GbE adapter"
				(path ""
					(reference "#PWR0217")
					(unit 1)
				)
			)
		)
	)
	(symbol
		(lib_id "antmicroCapacitors0402:C_1u_25V_0402")
		(at 335.28 113.03 90)
		(unit 1)
		(exclude_from_sim no)
		(in_bom yes)
		(on_board yes)
		(dnp no)
		(property "Reference" "C133"
			(at 337.312 109.22 90)
			(effects
				(font
					(size 1.27 1.27)
					(thickness 0.15)
				)
				(justify right)
			)
		)
		(property "Value" "C_1u_25V_0402"
			(at 345.44 92.71 0)
			(effects
				(font
					(size 1.27 1.27)
					(thickness 0.15)
				)
				(justify left bottom)
				(hide yes)
			)
		)
		(property "Footprint" "antmicro-footprints:C_0402_1005Metric"
			(at 347.98 92.71 0)
			(effects
				(font
					(size 1.27 1.27)
					(thickness 0.15)
				)
				(justify left bottom)
				(hide yes)
			)
		)
		(property "Datasheet" "https://www.murata.com/products/productdetail?partno=GRM155R61E105KE11%23"
			(at 350.52 92.71 0)
			(effects
				(font
					(size 1.27 1.27)
					(thickness 0.15)
				)
				(justify left bottom)
				(hide yes)
			)
		)
		(property "Description" "SMD Multilayer Ceramic Capacitor, 1 µF, 25 V, 0402 [1005 Metric], ± 10%, X5R, GRM Series"
			(at 335.28 113.03 0)
			(effects
				(font
					(size 1.27 1.27)
				)
				(hide yes)
			)
		)
		(property "MPN" "GRM155R61E105KE11J"
			(at 353.06 92.71 0)
			(effects
				(font
					(size 1.27 1.27)
					(thickness 0.15)
				)
				(justify left bottom)
				(hide yes)
			)
		)
		(property "Manufacturer" "Murata"
			(at 355.6 92.71 0)
			(effects
				(font
					(size 1.27 1.27)
					(thickness 0.15)
				)
				(justify left bottom)
				(hide yes)
			)
		)
		(property "License" "Apache-2.0"
			(at 358.14 92.71 0)
			(effects
				(font
					(size 1.27 1.27)
					(thickness 0.15)
				)
				(justify left bottom)
				(hide yes)
			)
		)
		(property "Author" "Antmicro"
			(at 360.68 92.71 0)
			(effects
				(font
					(size 1.27 1.27)
					(thickness 0.15)
				)
				(justify left bottom)
				(hide yes)
			)
		)
		(property "Val" "1u"
			(at 337.312 111.76 90)
			(effects
				(font
					(size 1.27 1.27)
					(thickness 0.15)
				)
				(justify right)
			)
		)
		(property "Voltage" "25V"
			(at 363.22 92.71 0)
			(effects
				(font
					(size 1.27 1.27)
				)
				(justify left bottom)
				(hide yes)
			)
		)
		(property "Dielectric" "X5R"
			(at 365.76 92.71 0)
			(effects
				(font
					(size 1.27 1.27)
				)
				(justify left bottom)
				(hide yes)
			)
		)
		(pin "2"
		)
		(pin "1"
		)
		(instances
			(project "OCuLink to 10GbE adapter"
				(path ""
					(reference "C133")
					(unit 1)
				)
			)
		)
	)
	(symbol
		(lib_id "antmicropower:GND")
		(at 353.06 115.57 0)
		(unit 1)
		(exclude_from_sim no)
		(in_bom yes)
		(on_board yes)
		(dnp no)
		(property "Reference" "#PWR0183"
			(at 361.95 118.11 0)
			(effects
				(font
					(size 1.27 1.27)
					(thickness 0.15)
				)
				(justify left bottom)
				(hide yes)
			)
		)
		(property "Value" "GND"
			(at 353.06 119.38 0)
			(effects
				(font
					(size 1.27 1.27)
					(thickness 0.15)
				)
			)
		)
		(property "Footprint" ""
			(at 361.95 123.19 0)
			(effects
				(font
					(size 1.27 1.27)
					(thickness 0.15)
				)
				(justify left bottom)
				(hide yes)
			)
		)
		(property "Datasheet" ""
			(at 361.95 128.27 0)
			(effects
				(font
					(size 1.27 1.27)
					(thickness 0.15)
				)
				(justify left bottom)
				(hide yes)
			)
		)
		(property "Description" ""
			(at 353.06 115.57 0)
			(effects
				(font
					(size 1.27 1.27)
				)
				(hide yes)
			)
		)
		(property "Author" "Antmicro"
			(at 361.95 123.19 0)
			(effects
				(font
					(size 1.27 1.27)
					(thickness 0.15)
				)
				(justify left bottom)
				(hide yes)
			)
		)
		(property "License" "Apache-2.0"
			(at 361.95 125.73 0)
			(effects
				(font
					(size 1.27 1.27)
					(thickness 0.15)
				)
				(justify left bottom)
				(hide yes)
			)
		)
		(pin "1"
		)
		(instances
			(project "OCuLink to 10GbE adapter"
				(path ""
					(reference "#PWR0183")
					(unit 1)
				)
			)
		)
	)
	(symbol
		(lib_id "antmicroCapacitors0603:C_10u_10V_X7R_0603")
		(at 317.5 130.81 90)
		(unit 1)
		(exclude_from_sim no)
		(in_bom yes)
		(on_board yes)
		(dnp no)
		(property "Reference" "C148"
			(at 319.532 127 90)
			(effects
				(font
					(size 1.27 1.27)
					(thickness 0.15)
				)
				(justify right)
			)
		)
		(property "Value" "C_10u_10V_X7R_0603"
			(at 327.66 115.57 0)
			(effects
				(font
					(size 1.27 1.27)
					(thickness 0.15)
				)
				(justify left bottom)
				(hide yes)
			)
		)
		(property "Footprint" "antmicro-footprints:C_0603_1608Metric"
			(at 330.2 115.57 0)
			(effects
				(font
					(size 1.27 1.27)
					(thickness 0.15)
				)
				(justify left bottom)
				(hide yes)
			)
		)
		(property "Datasheet" "https://www.murata.com/products/productdetail?partno=GRM188Z71A106KA73%23"
			(at 332.74 115.57 0)
			(effects
				(font
					(size 1.27 1.27)
					(thickness 0.15)
				)
				(justify left bottom)
				(hide yes)
			)
		)
		(property "Description" "SMD Multilayer Ceramic Capacitor,  10µF, 10V, 0603, ±10%, X7R"
			(at 317.5 130.81 0)
			(effects
				(font
					(size 1.27 1.27)
				)
				(hide yes)
			)
		)
		(property "MPN" "GRM188Z71A106KA73D"
			(at 335.28 115.57 0)
			(effects
				(font
					(size 1.27 1.27)
					(thickness 0.15)
				)
				(justify left bottom)
				(hide yes)
			)
		)
		(property "Val" "10u"
			(at 319.532 129.54 90)
			(effects
				(font
					(size 1.27 1.27)
					(thickness 0.15)
				)
				(justify right)
			)
		)
		(property "Voltage" "10V"
			(at 337.82 115.57 0)
			(effects
				(font
					(size 1.27 1.27)
					(thickness 0.15)
				)
				(justify left bottom)
				(hide yes)
			)
		)
		(property "Dielectric" "X7R"
			(at 340.36 115.57 0)
			(effects
				(font
					(size 1.27 1.27)
					(thickness 0.15)
				)
				(justify left bottom)
				(hide yes)
			)
		)
		(property "Manufacturer" "Murata"
			(at 342.9 115.57 0)
			(effects
				(font
					(size 1.27 1.27)
					(thickness 0.15)
				)
				(justify left bottom)
				(hide yes)
			)
		)
		(property "License" "Apache-2.0"
			(at 345.44 115.57 0)
			(effects
				(font
					(size 1.27 1.27)
					(thickness 0.15)
				)
				(justify left bottom)
				(hide yes)
			)
		)
		(property "Author" "Antmicro"
			(at 347.98 115.57 0)
			(effects
				(font
					(size 1.27 1.27)
					(thickness 0.15)
				)
				(justify left bottom)
				(hide yes)
			)
		)
		(pin "1"
		)
		(pin "2"
		)
		(instances
			(project "OCuLink to 10GbE adapter"
				(path ""
					(reference "C148")
					(unit 1)
				)
			)
		)
	)
	(symbol
		(lib_id "antmicroCapacitors0402:C_1u_25V_0402")
		(at 397.51 52.07 90)
		(unit 1)
		(exclude_from_sim no)
		(in_bom yes)
		(on_board yes)
		(dnp no)
		(property "Reference" "C98"
			(at 399.542 48.26 90)
			(effects
				(font
					(size 1.27 1.27)
					(thickness 0.15)
				)
				(justify right)
			)
		)
		(property "Value" "C_1u_25V_0402"
			(at 407.67 31.75 0)
			(effects
				(font
					(size 1.27 1.27)
					(thickness 0.15)
				)
				(justify left bottom)
				(hide yes)
			)
		)
		(property "Footprint" "antmicro-footprints:C_0402_1005Metric"
			(at 410.21 31.75 0)
			(effects
				(font
					(size 1.27 1.27)
					(thickness 0.15)
				)
				(justify left bottom)
				(hide yes)
			)
		)
		(property "Datasheet" "https://www.murata.com/products/productdetail?partno=GRM155R61E105KE11%23"
			(at 412.75 31.75 0)
			(effects
				(font
					(size 1.27 1.27)
					(thickness 0.15)
				)
				(justify left bottom)
				(hide yes)
			)
		)
		(property "Description" "SMD Multilayer Ceramic Capacitor, 1 µF, 25 V, 0402 [1005 Metric], ± 10%, X5R, GRM Series"
			(at 397.51 52.07 0)
			(effects
				(font
					(size 1.27 1.27)
				)
				(hide yes)
			)
		)
		(property "MPN" "GRM155R61E105KE11J"
			(at 415.29 31.75 0)
			(effects
				(font
					(size 1.27 1.27)
					(thickness 0.15)
				)
				(justify left bottom)
				(hide yes)
			)
		)
		(property "Manufacturer" "Murata"
			(at 417.83 31.75 0)
			(effects
				(font
					(size 1.27 1.27)
					(thickness 0.15)
				)
				(justify left bottom)
				(hide yes)
			)
		)
		(property "License" "Apache-2.0"
			(at 420.37 31.75 0)
			(effects
				(font
					(size 1.27 1.27)
					(thickness 0.15)
				)
				(justify left bottom)
				(hide yes)
			)
		)
		(property "Author" "Antmicro"
			(at 422.91 31.75 0)
			(effects
				(font
					(size 1.27 1.27)
					(thickness 0.15)
				)
				(justify left bottom)
				(hide yes)
			)
		)
		(property "Val" "1u"
			(at 399.542 50.8 90)
			(effects
				(font
					(size 1.27 1.27)
					(thickness 0.15)
				)
				(justify right)
			)
		)
		(property "Voltage" "25V"
			(at 425.45 31.75 0)
			(effects
				(font
					(size 1.27 1.27)
				)
				(justify left bottom)
				(hide yes)
			)
		)
		(property "Dielectric" "X5R"
			(at 427.99 31.75 0)
			(effects
				(font
					(size 1.27 1.27)
				)
				(justify left bottom)
				(hide yes)
			)
		)
		(pin "2"
		)
		(pin "1"
		)
		(instances
			(project "OCuLink to 10GbE adapter"
				(path ""
					(reference "C98")
					(unit 1)
				)
			)
		)
	)
	(symbol
		(lib_id "antmicropower:GND")
		(at 88.9 76.2 0)
		(unit 1)
		(exclude_from_sim no)
		(in_bom yes)
		(on_board yes)
		(dnp no)
		(property "Reference" "#PWR0135"
			(at 97.79 78.74 0)
			(effects
				(font
					(size 1.27 1.27)
					(thickness 0.15)
				)
				(justify left bottom)
				(hide yes)
			)
		)
		(property "Value" "GND"
			(at 88.9 80.01 0)
			(effects
				(font
					(size 1.27 1.27)
					(thickness 0.15)
				)
			)
		)
		(property "Footprint" ""
			(at 97.79 83.82 0)
			(effects
				(font
					(size 1.27 1.27)
					(thickness 0.15)
				)
				(justify left bottom)
				(hide yes)
			)
		)
		(property "Datasheet" ""
			(at 97.79 88.9 0)
			(effects
				(font
					(size 1.27 1.27)
					(thickness 0.15)
				)
				(justify left bottom)
				(hide yes)
			)
		)
		(property "Description" ""
			(at 88.9 76.2 0)
			(effects
				(font
					(size 1.27 1.27)
				)
				(hide yes)
			)
		)
		(property "Author" "Antmicro"
			(at 97.79 83.82 0)
			(effects
				(font
					(size 1.27 1.27)
					(thickness 0.15)
				)
				(justify left bottom)
				(hide yes)
			)
		)
		(property "License" "Apache-2.0"
			(at 97.79 86.36 0)
			(effects
				(font
					(size 1.27 1.27)
					(thickness 0.15)
				)
				(justify left bottom)
				(hide yes)
			)
		)
		(pin "1"
		)
		(instances
			(project "OCuLink to 10GbE adapter"
				(path ""
					(reference "#PWR0135")
					(unit 1)
				)
			)
		)
	)
	(symbol
		(lib_id "antmicropower:VDD")
		(at 166.37 78.74 0)
		(unit 1)
		(exclude_from_sim no)
		(in_bom yes)
		(on_board yes)
		(dnp no)
		(property "Reference" "#PWR0154"
			(at 166.37 82.55 0)
			(effects
				(font
					(size 1.27 1.27)
				)
				(hide yes)
			)
		)
		(property "Value" "P1_AVDDL"
			(at 166.37 74.93 0)
			(effects
				(font
					(size 1.27 1.27)
				)
			)
		)
		(property "Footprint" ""
			(at 166.37 78.74 0)
			(effects
				(font
					(size 1.27 1.27)
				)
				(hide yes)
			)
		)
		(property "Datasheet" ""
			(at 166.37 78.74 0)
			(effects
				(font
					(size 1.27 1.27)
				)
				(hide yes)
			)
		)
		(property "Description" ""
			(at 166.37 78.74 0)
			(effects
				(font
					(size 1.27 1.27)
				)
				(hide yes)
			)
		)
		(pin "1"
		)
		(instances
			(project "OCuLink to 10GbE adapter"
				(path ""
					(reference "#PWR0154")
					(unit 1)
				)
			)
		)
	)
	(symbol
		(lib_id "antmicroCapacitors0603:C_47u_0603")
		(at 54.61 207.01 90)
		(unit 1)
		(exclude_from_sim no)
		(in_bom yes)
		(on_board yes)
		(dnp no)
		(property "Reference" "C180"
			(at 56.642 203.2 90)
			(effects
				(font
					(size 1.27 1.27)
					(thickness 0.15)
				)
				(justify right)
			)
		)
		(property "Value" "C_47u_0603"
			(at 64.77 186.69 0)
			(effects
				(font
					(size 1.27 1.27)
					(thickness 0.15)
				)
				(justify left bottom)
				(hide yes)
			)
		)
		(property "Footprint" "antmicro-footprints:C_0603_1608Metric"
			(at 67.31 186.69 0)
			(effects
				(font
					(size 1.27 1.27)
					(thickness 0.15)
				)
				(justify left bottom)
				(hide yes)
			)
		)
		(property "Datasheet" "https://www.murata.com/products/productdetail?partno=GRM188R60J476ME15%23"
			(at 69.85 186.69 0)
			(effects
				(font
					(size 1.27 1.27)
					(thickness 0.15)
				)
				(justify left bottom)
				(hide yes)
			)
		)
		(property "Description" "SMD Multilayer Ceramic Capacitor, 47 µF, 6.3 V, 0603 [1608 Metric], ± 20%, X5R, GRM Series"
			(at 87.63 186.69 0)
			(effects
				(font
					(size 1.27 1.27)
				)
				(justify left bottom)
				(hide yes)
			)
		)
		(property "MPN" "GRM188R60J476ME15D"
			(at 72.39 186.69 0)
			(effects
				(font
					(size 1.27 1.27)
					(thickness 0.15)
				)
				(justify left bottom)
				(hide yes)
			)
		)
		(property "Manufacturer" "Murata"
			(at 74.93 186.69 0)
			(effects
				(font
					(size 1.27 1.27)
					(thickness 0.15)
				)
				(justify left bottom)
				(hide yes)
			)
		)
		(property "License" "Apache-2.0"
			(at 77.47 186.69 0)
			(effects
				(font
					(size 1.27 1.27)
					(thickness 0.15)
				)
				(justify left bottom)
				(hide yes)
			)
		)
		(property "Author" "Antmicro"
			(at 80.01 186.69 0)
			(effects
				(font
					(size 1.27 1.27)
					(thickness 0.15)
				)
				(justify left bottom)
				(hide yes)
			)
		)
		(property "Val" "47u"
			(at 56.642 205.74 90)
			(effects
				(font
					(size 1.27 1.27)
					(thickness 0.15)
				)
				(justify right)
			)
		)
		(property "Voltage" ""
			(at 82.55 186.69 0)
			(effects
				(font
					(size 1.27 1.27)
				)
				(justify left bottom)
				(hide yes)
			)
		)
		(property "Dielectric" ""
			(at 85.09 186.69 0)
			(effects
				(font
					(size 1.27 1.27)
				)
				(justify left bottom)
				(hide yes)
			)
		)
		(pin "1"
		)
		(pin "2"
		)
		(instances
			(project ""
				(path ""
					(reference "C180")
					(unit 1)
				)
			)
		)
	)
	(symbol
		(lib_id "antmicropower:GND")
		(at 53.34 54.61 0)
		(unit 1)
		(exclude_from_sim no)
		(in_bom yes)
		(on_board yes)
		(dnp no)
		(property "Reference" "#PWR0114"
			(at 62.23 57.15 0)
			(effects
				(font
					(size 1.27 1.27)
					(thickness 0.15)
				)
				(justify left bottom)
				(hide yes)
			)
		)
		(property "Value" "GND"
			(at 53.34 58.42 0)
			(effects
				(font
					(size 1.27 1.27)
					(thickness 0.15)
				)
			)
		)
		(property "Footprint" ""
			(at 62.23 62.23 0)
			(effects
				(font
					(size 1.27 1.27)
					(thickness 0.15)
				)
				(justify left bottom)
				(hide yes)
			)
		)
		(property "Datasheet" ""
			(at 62.23 67.31 0)
			(effects
				(font
					(size 1.27 1.27)
					(thickness 0.15)
				)
				(justify left bottom)
				(hide yes)
			)
		)
		(property "Description" ""
			(at 53.34 54.61 0)
			(effects
				(font
					(size 1.27 1.27)
				)
				(hide yes)
			)
		)
		(property "Author" "Antmicro"
			(at 62.23 62.23 0)
			(effects
				(font
					(size 1.27 1.27)
					(thickness 0.15)
				)
				(justify left bottom)
				(hide yes)
			)
		)
		(property "License" "Apache-2.0"
			(at 62.23 64.77 0)
			(effects
				(font
					(size 1.27 1.27)
					(thickness 0.15)
				)
				(justify left bottom)
				(hide yes)
			)
		)
		(pin "1"
		)
		(instances
			(project "OCuLink to 10GbE adapter"
				(path ""
					(reference "#PWR0114")
					(unit 1)
				)
			)
		)
	)
	(symbol
		(lib_id "antmicroCapacitors0402:C_1u_25V_0402")
		(at 397.51 73.66 90)
		(unit 1)
		(exclude_from_sim no)
		(in_bom yes)
		(on_board yes)
		(dnp no)
		(property "Reference" "C116"
			(at 399.542 69.85 90)
			(effects
				(font
					(size 1.27 1.27)
					(thickness 0.15)
				)
				(justify right)
			)
		)
		(property "Value" "C_1u_25V_0402"
			(at 407.67 53.34 0)
			(effects
				(font
					(size 1.27 1.27)
					(thickness 0.15)
				)
				(justify left bottom)
				(hide yes)
			)
		)
		(property "Footprint" "antmicro-footprints:C_0402_1005Metric"
			(at 410.21 53.34 0)
			(effects
				(font
					(size 1.27 1.27)
					(thickness 0.15)
				)
				(justify left bottom)
				(hide yes)
			)
		)
		(property "Datasheet" "https://www.murata.com/products/productdetail?partno=GRM155R61E105KE11%23"
			(at 412.75 53.34 0)
			(effects
				(font
					(size 1.27 1.27)
					(thickness 0.15)
				)
				(justify left bottom)
				(hide yes)
			)
		)
		(property "Description" "SMD Multilayer Ceramic Capacitor, 1 µF, 25 V, 0402 [1005 Metric], ± 10%, X5R, GRM Series"
			(at 397.51 73.66 0)
			(effects
				(font
					(size 1.27 1.27)
				)
				(hide yes)
			)
		)
		(property "MPN" "GRM155R61E105KE11J"
			(at 415.29 53.34 0)
			(effects
				(font
					(size 1.27 1.27)
					(thickness 0.15)
				)
				(justify left bottom)
				(hide yes)
			)
		)
		(property "Manufacturer" "Murata"
			(at 417.83 53.34 0)
			(effects
				(font
					(size 1.27 1.27)
					(thickness 0.15)
				)
				(justify left bottom)
				(hide yes)
			)
		)
		(property "License" "Apache-2.0"
			(at 420.37 53.34 0)
			(effects
				(font
					(size 1.27 1.27)
					(thickness 0.15)
				)
				(justify left bottom)
				(hide yes)
			)
		)
		(property "Author" "Antmicro"
			(at 422.91 53.34 0)
			(effects
				(font
					(size 1.27 1.27)
					(thickness 0.15)
				)
				(justify left bottom)
				(hide yes)
			)
		)
		(property "Val" "1u"
			(at 399.542 72.39 90)
			(effects
				(font
					(size 1.27 1.27)
					(thickness 0.15)
				)
				(justify right)
			)
		)
		(property "Voltage" "25V"
			(at 425.45 53.34 0)
			(effects
				(font
					(size 1.27 1.27)
				)
				(justify left bottom)
				(hide yes)
			)
		)
		(property "Dielectric" "X5R"
			(at 427.99 53.34 0)
			(effects
				(font
					(size 1.27 1.27)
				)
				(justify left bottom)
				(hide yes)
			)
		)
		(pin "2"
		)
		(pin "1"
		)
		(instances
			(project "OCuLink to 10GbE adapter"
				(path ""
					(reference "C116")
					(unit 1)
				)
			)
		)
	)
	(symbol
		(lib_id "antmicroCapacitors0402:C_1u_25V_0402")
		(at 317.5 73.66 90)
		(unit 1)
		(exclude_from_sim no)
		(in_bom yes)
		(on_board yes)
		(dnp no)
		(property "Reference" "C107"
			(at 319.532 69.85 90)
			(effects
				(font
					(size 1.27 1.27)
					(thickness 0.15)
				)
				(justify right)
			)
		)
		(property "Value" "C_1u_25V_0402"
			(at 327.66 53.34 0)
			(effects
				(font
					(size 1.27 1.27)
					(thickness 0.15)
				)
				(justify left bottom)
				(hide yes)
			)
		)
		(property "Footprint" "antmicro-footprints:C_0402_1005Metric"
			(at 330.2 53.34 0)
			(effects
				(font
					(size 1.27 1.27)
					(thickness 0.15)
				)
				(justify left bottom)
				(hide yes)
			)
		)
		(property "Datasheet" "https://www.murata.com/products/productdetail?partno=GRM155R61E105KE11%23"
			(at 332.74 53.34 0)
			(effects
				(font
					(size 1.27 1.27)
					(thickness 0.15)
				)
				(justify left bottom)
				(hide yes)
			)
		)
		(property "Description" "SMD Multilayer Ceramic Capacitor, 1 µF, 25 V, 0402 [1005 Metric], ± 10%, X5R, GRM Series"
			(at 317.5 73.66 0)
			(effects
				(font
					(size 1.27 1.27)
				)
				(hide yes)
			)
		)
		(property "MPN" "GRM155R61E105KE11J"
			(at 335.28 53.34 0)
			(effects
				(font
					(size 1.27 1.27)
					(thickness 0.15)
				)
				(justify left bottom)
				(hide yes)
			)
		)
		(property "Manufacturer" "Murata"
			(at 337.82 53.34 0)
			(effects
				(font
					(size 1.27 1.27)
					(thickness 0.15)
				)
				(justify left bottom)
				(hide yes)
			)
		)
		(property "License" "Apache-2.0"
			(at 340.36 53.34 0)
			(effects
				(font
					(size 1.27 1.27)
					(thickness 0.15)
				)
				(justify left bottom)
				(hide yes)
			)
		)
		(property "Author" "Antmicro"
			(at 342.9 53.34 0)
			(effects
				(font
					(size 1.27 1.27)
					(thickness 0.15)
				)
				(justify left bottom)
				(hide yes)
			)
		)
		(property "Val" "1u"
			(at 319.532 72.39 90)
			(effects
				(font
					(size 1.27 1.27)
					(thickness 0.15)
				)
				(justify right)
			)
		)
		(property "Voltage" "25V"
			(at 345.44 53.34 0)
			(effects
				(font
					(size 1.27 1.27)
				)
				(justify left bottom)
				(hide yes)
			)
		)
		(property "Dielectric" "X5R"
			(at 347.98 53.34 0)
			(effects
				(font
					(size 1.27 1.27)
				)
				(justify left bottom)
				(hide yes)
			)
		)
		(pin "2"
		)
		(pin "1"
		)
		(instances
			(project "OCuLink to 10GbE adapter"
				(path ""
					(reference "C107")
					(unit 1)
				)
			)
		)
	)
	(symbol
		(lib_id "antmicropower:GND")
		(at 44.45 54.61 0)
		(unit 1)
		(exclude_from_sim no)
		(in_bom yes)
		(on_board yes)
		(dnp no)
		(property "Reference" "#PWR0113"
			(at 53.34 57.15 0)
			(effects
				(font
					(size 1.27 1.27)
					(thickness 0.15)
				)
				(justify left bottom)
				(hide yes)
			)
		)
		(property "Value" "GND"
			(at 44.45 58.42 0)
			(effects
				(font
					(size 1.27 1.27)
					(thickness 0.15)
				)
			)
		)
		(property "Footprint" ""
			(at 53.34 62.23 0)
			(effects
				(font
					(size 1.27 1.27)
					(thickness 0.15)
				)
				(justify left bottom)
				(hide yes)
			)
		)
		(property "Datasheet" ""
			(at 53.34 67.31 0)
			(effects
				(font
					(size 1.27 1.27)
					(thickness 0.15)
				)
				(justify left bottom)
				(hide yes)
			)
		)
		(property "Description" ""
			(at 44.45 54.61 0)
			(effects
				(font
					(size 1.27 1.27)
				)
				(hide yes)
			)
		)
		(property "Author" "Antmicro"
			(at 53.34 62.23 0)
			(effects
				(font
					(size 1.27 1.27)
					(thickness 0.15)
				)
				(justify left bottom)
				(hide yes)
			)
		)
		(property "License" "Apache-2.0"
			(at 53.34 64.77 0)
			(effects
				(font
					(size 1.27 1.27)
					(thickness 0.15)
				)
				(justify left bottom)
				(hide yes)
			)
		)
		(pin "1"
		)
		(instances
			(project "OCuLink to 10GbE adapter"
				(path ""
					(reference "#PWR0113")
					(unit 1)
				)
			)
		)
	)
	(symbol
		(lib_id "antmicroCapacitors0402:C_1u_25V_0402")
		(at 379.73 52.07 90)
		(unit 1)
		(exclude_from_sim no)
		(in_bom yes)
		(on_board yes)
		(dnp no)
		(property "Reference" "C96"
			(at 381.762 48.26 90)
			(effects
				(font
					(size 1.27 1.27)
					(thickness 0.15)
				)
				(justify right)
			)
		)
		(property "Value" "C_1u_25V_0402"
			(at 389.89 31.75 0)
			(effects
				(font
					(size 1.27 1.27)
					(thickness 0.15)
				)
				(justify left bottom)
				(hide yes)
			)
		)
		(property "Footprint" "antmicro-footprints:C_0402_1005Metric"
			(at 392.43 31.75 0)
			(effects
				(font
					(size 1.27 1.27)
					(thickness 0.15)
				)
				(justify left bottom)
				(hide yes)
			)
		)
		(property "Datasheet" "https://www.murata.com/products/productdetail?partno=GRM155R61E105KE11%23"
			(at 394.97 31.75 0)
			(effects
				(font
					(size 1.27 1.27)
					(thickness 0.15)
				)
				(justify left bottom)
				(hide yes)
			)
		)
		(property "Description" "SMD Multilayer Ceramic Capacitor, 1 µF, 25 V, 0402 [1005 Metric], ± 10%, X5R, GRM Series"
			(at 379.73 52.07 0)
			(effects
				(font
					(size 1.27 1.27)
				)
				(hide yes)
			)
		)
		(property "MPN" "GRM155R61E105KE11J"
			(at 397.51 31.75 0)
			(effects
				(font
					(size 1.27 1.27)
					(thickness 0.15)
				)
				(justify left bottom)
				(hide yes)
			)
		)
		(property "Manufacturer" "Murata"
			(at 400.05 31.75 0)
			(effects
				(font
					(size 1.27 1.27)
					(thickness 0.15)
				)
				(justify left bottom)
				(hide yes)
			)
		)
		(property "License" "Apache-2.0"
			(at 402.59 31.75 0)
			(effects
				(font
					(size 1.27 1.27)
					(thickness 0.15)
				)
				(justify left bottom)
				(hide yes)
			)
		)
		(property "Author" "Antmicro"
			(at 405.13 31.75 0)
			(effects
				(font
					(size 1.27 1.27)
					(thickness 0.15)
				)
				(justify left bottom)
				(hide yes)
			)
		)
		(property "Val" "1u"
			(at 381.762 50.8 90)
			(effects
				(font
					(size 1.27 1.27)
					(thickness 0.15)
				)
				(justify right)
			)
		)
		(property "Voltage" "25V"
			(at 407.67 31.75 0)
			(effects
				(font
					(size 1.27 1.27)
				)
				(justify left bottom)
				(hide yes)
			)
		)
		(property "Dielectric" "X5R"
			(at 410.21 31.75 0)
			(effects
				(font
					(size 1.27 1.27)
				)
				(justify left bottom)
				(hide yes)
			)
		)
		(pin "2"
		)
		(pin "1"
		)
		(instances
			(project "OCuLink to 10GbE adapter"
				(path ""
					(reference "C96")
					(unit 1)
				)
			)
		)
	)
	(symbol
		(lib_id "antmicropower:+3V3")
		(at 283.21 78.74 0)
		(unit 1)
		(exclude_from_sim no)
		(in_bom yes)
		(on_board yes)
		(dnp no)
		(property "Reference" "#PWR0162"
			(at 298.45 78.74 0)
			(effects
				(font
					(size 1.27 1.27)
					(thickness 0.15)
				)
				(justify left bottom)
				(hide yes)
			)
		)
		(property "Value" "+3V3"
			(at 283.21 74.93 0)
			(effects
				(font
					(size 1.27 1.27)
					(thickness 0.15)
				)
			)
		)
		(property "Footprint" ""
			(at 298.45 86.36 0)
			(effects
				(font
					(size 1.27 1.27)
					(thickness 0.15)
				)
				(justify left bottom)
				(hide yes)
			)
		)
		(property "Datasheet" ""
			(at 298.45 88.9 0)
			(effects
				(font
					(size 1.27 1.27)
					(thickness 0.15)
				)
				(justify left bottom)
				(hide yes)
			)
		)
		(property "Description" ""
			(at 283.21 78.74 0)
			(effects
				(font
					(size 1.27 1.27)
				)
				(hide yes)
			)
		)
		(property "Author" "Antmicro"
			(at 298.45 81.28 0)
			(effects
				(font
					(size 1.27 1.27)
					(thickness 0.15)
				)
				(justify left bottom)
				(hide yes)
			)
		)
		(property "License" "Apache-2.0"
			(at 298.45 83.82 0)
			(effects
				(font
					(size 1.27 1.27)
					(thickness 0.15)
				)
				(justify left bottom)
				(hide yes)
			)
		)
		(pin "1"
		)
		(instances
			(project "OCuLink to 10GbE adapter"
				(path ""
					(reference "#PWR0162")
					(unit 1)
				)
			)
		)
	)
	(symbol
		(lib_id "antmicropower:GND")
		(at 88.9 54.61 0)
		(unit 1)
		(exclude_from_sim no)
		(in_bom yes)
		(on_board yes)
		(dnp no)
		(property "Reference" "#PWR0117"
			(at 97.79 57.15 0)
			(effects
				(font
					(size 1.27 1.27)
					(thickness 0.15)
				)
				(justify left bottom)
				(hide yes)
			)
		)
		(property "Value" "GND"
			(at 88.9 58.42 0)
			(effects
				(font
					(size 1.27 1.27)
					(thickness 0.15)
				)
			)
		)
		(property "Footprint" ""
			(at 97.79 62.23 0)
			(effects
				(font
					(size 1.27 1.27)
					(thickness 0.15)
				)
				(justify left bottom)
				(hide yes)
			)
		)
		(property "Datasheet" ""
			(at 97.79 67.31 0)
			(effects
				(font
					(size 1.27 1.27)
					(thickness 0.15)
				)
				(justify left bottom)
				(hide yes)
			)
		)
		(property "Description" ""
			(at 88.9 54.61 0)
			(effects
				(font
					(size 1.27 1.27)
				)
				(hide yes)
			)
		)
		(property "Author" "Antmicro"
			(at 97.79 62.23 0)
			(effects
				(font
					(size 1.27 1.27)
					(thickness 0.15)
				)
				(justify left bottom)
				(hide yes)
			)
		)
		(property "License" "Apache-2.0"
			(at 97.79 64.77 0)
			(effects
				(font
					(size 1.27 1.27)
					(thickness 0.15)
				)
				(justify left bottom)
				(hide yes)
			)
		)
		(pin "1"
		)
		(instances
			(project "OCuLink to 10GbE adapter"
				(path ""
					(reference "#PWR0117")
					(unit 1)
				)
			)
		)
	)
	(symbol
		(lib_id "antmicropower:GND")
		(at 97.79 129.54 0)
		(unit 1)
		(exclude_from_sim no)
		(in_bom yes)
		(on_board yes)
		(dnp no)
		(property "Reference" "#PWR0192"
			(at 106.68 132.08 0)
			(effects
				(font
					(size 1.27 1.27)
					(thickness 0.15)
				)
				(justify left bottom)
				(hide yes)
			)
		)
		(property "Value" "GND"
			(at 97.79 133.35 0)
			(effects
				(font
					(size 1.27 1.27)
					(thickness 0.15)
				)
			)
		)
		(property "Footprint" ""
			(at 106.68 137.16 0)
			(effects
				(font
					(size 1.27 1.27)
					(thickness 0.15)
				)
				(justify left bottom)
				(hide yes)
			)
		)
		(property "Datasheet" ""
			(at 106.68 142.24 0)
			(effects
				(font
					(size 1.27 1.27)
					(thickness 0.15)
				)
				(justify left bottom)
				(hide yes)
			)
		)
		(property "Description" ""
			(at 97.79 129.54 0)
			(effects
				(font
					(size 1.27 1.27)
				)
				(hide yes)
			)
		)
		(property "Author" "Antmicro"
			(at 106.68 137.16 0)
			(effects
				(font
					(size 1.27 1.27)
					(thickness 0.15)
				)
				(justify left bottom)
				(hide yes)
			)
		)
		(property "License" "Apache-2.0"
			(at 106.68 139.7 0)
			(effects
				(font
					(size 1.27 1.27)
					(thickness 0.15)
				)
				(justify left bottom)
				(hide yes)
			)
		)
		(pin "1"
		)
		(instances
			(project "OCuLink to 10GbE adapter"
				(path ""
					(reference "#PWR0192")
					(unit 1)
				)
			)
		)
	)
	(symbol
		(lib_id "antmicropower:GND")
		(at 53.34 182.88 0)
		(unit 1)
		(exclude_from_sim no)
		(in_bom yes)
		(on_board yes)
		(dnp no)
		(property "Reference" "#PWR0224"
			(at 62.23 185.42 0)
			(effects
				(font
					(size 1.27 1.27)
					(thickness 0.15)
				)
				(justify left bottom)
				(hide yes)
			)
		)
		(property "Value" "GND"
			(at 53.34 186.69 0)
			(effects
				(font
					(size 1.27 1.27)
					(thickness 0.15)
				)
			)
		)
		(property "Footprint" ""
			(at 62.23 190.5 0)
			(effects
				(font
					(size 1.27 1.27)
					(thickness 0.15)
				)
				(justify left bottom)
				(hide yes)
			)
		)
		(property "Datasheet" ""
			(at 62.23 195.58 0)
			(effects
				(font
					(size 1.27 1.27)
					(thickness 0.15)
				)
				(justify left bottom)
				(hide yes)
			)
		)
		(property "Description" ""
			(at 53.34 182.88 0)
			(effects
				(font
					(size 1.27 1.27)
				)
				(hide yes)
			)
		)
		(property "Author" "Antmicro"
			(at 62.23 190.5 0)
			(effects
				(font
					(size 1.27 1.27)
					(thickness 0.15)
				)
				(justify left bottom)
				(hide yes)
			)
		)
		(property "License" "Apache-2.0"
			(at 62.23 193.04 0)
			(effects
				(font
					(size 1.27 1.27)
					(thickness 0.15)
				)
				(justify left bottom)
				(hide yes)
			)
		)
		(pin "1"
		)
		(instances
			(project "OCuLink to 10GbE adapter"
				(path ""
					(reference "#PWR0224")
					(unit 1)
				)
			)
		)
	)
	(symbol
		(lib_id "antmicroCapacitors0402:C_1u_25V_0402")
		(at 88.9 127 90)
		(unit 1)
		(exclude_from_sim no)
		(in_bom yes)
		(on_board yes)
		(dnp no)
		(property "Reference" "C142"
			(at 90.678 123.19 90)
			(effects
				(font
					(size 1.27 1.27)
					(thickness 0.15)
				)
				(justify right)
			)
		)
		(property "Value" "C_1u_25V_0402"
			(at 99.06 106.68 0)
			(effects
				(font
					(size 1.27 1.27)
					(thickness 0.15)
				)
				(justify left bottom)
				(hide yes)
			)
		)
		(property "Footprint" "antmicro-footprints:C_0402_1005Metric"
			(at 101.6 106.68 0)
			(effects
				(font
					(size 1.27 1.27)
					(thickness 0.15)
				)
				(justify left bottom)
				(hide yes)
			)
		)
		(property "Datasheet" "https://www.murata.com/products/productdetail?partno=GRM155R61E105KE11%23"
			(at 104.14 106.68 0)
			(effects
				(font
					(size 1.27 1.27)
					(thickness 0.15)
				)
				(justify left bottom)
				(hide yes)
			)
		)
		(property "Description" "SMD Multilayer Ceramic Capacitor, 1 µF, 25 V, 0402 [1005 Metric], ± 10%, X5R, GRM Series"
			(at 88.9 127 0)
			(effects
				(font
					(size 1.27 1.27)
				)
				(hide yes)
			)
		)
		(property "MPN" "GRM155R61E105KE11J"
			(at 106.68 106.68 0)
			(effects
				(font
					(size 1.27 1.27)
					(thickness 0.15)
				)
				(justify left bottom)
				(hide yes)
			)
		)
		(property "Manufacturer" "Murata"
			(at 109.22 106.68 0)
			(effects
				(font
					(size 1.27 1.27)
					(thickness 0.15)
				)
				(justify left bottom)
				(hide yes)
			)
		)
		(property "License" "Apache-2.0"
			(at 111.76 106.68 0)
			(effects
				(font
					(size 1.27 1.27)
					(thickness 0.15)
				)
				(justify left bottom)
				(hide yes)
			)
		)
		(property "Author" "Antmicro"
			(at 114.3 106.68 0)
			(effects
				(font
					(size 1.27 1.27)
					(thickness 0.15)
				)
				(justify left bottom)
				(hide yes)
			)
		)
		(property "Val" "1u"
			(at 90.678 125.73 90)
			(effects
				(font
					(size 1.27 1.27)
					(thickness 0.15)
				)
				(justify right)
			)
		)
		(property "Voltage" "25V"
			(at 116.84 106.68 0)
			(effects
				(font
					(size 1.27 1.27)
				)
				(justify left bottom)
				(hide yes)
			)
		)
		(property "Dielectric" "X5R"
			(at 119.38 106.68 0)
			(effects
				(font
					(size 1.27 1.27)
				)
				(justify left bottom)
				(hide yes)
			)
		)
		(pin "2"
		)
		(pin "1"
		)
		(instances
			(project "OCuLink to 10GbE adapter"
				(path ""
					(reference "C142")
					(unit 1)
				)
			)
		)
	)
	(symbol
		(lib_id "antmicropower:GND")
		(at 106.68 54.61 0)
		(unit 1)
		(exclude_from_sim no)
		(in_bom yes)
		(on_board yes)
		(dnp no)
		(property "Reference" "#PWR0119"
			(at 115.57 57.15 0)
			(effects
				(font
					(size 1.27 1.27)
					(thickness 0.15)
				)
				(justify left bottom)
				(hide yes)
			)
		)
		(property "Value" "GND"
			(at 106.68 58.42 0)
			(effects
				(font
					(size 1.27 1.27)
					(thickness 0.15)
				)
			)
		)
		(property "Footprint" ""
			(at 115.57 62.23 0)
			(effects
				(font
					(size 1.27 1.27)
					(thickness 0.15)
				)
				(justify left bottom)
				(hide yes)
			)
		)
		(property "Datasheet" ""
			(at 115.57 67.31 0)
			(effects
				(font
					(size 1.27 1.27)
					(thickness 0.15)
				)
				(justify left bottom)
				(hide yes)
			)
		)
		(property "Description" ""
			(at 106.68 54.61 0)
			(effects
				(font
					(size 1.27 1.27)
				)
				(hide yes)
			)
		)
		(property "Author" "Antmicro"
			(at 115.57 62.23 0)
			(effects
				(font
					(size 1.27 1.27)
					(thickness 0.15)
				)
				(justify left bottom)
				(hide yes)
			)
		)
		(property "License" "Apache-2.0"
			(at 115.57 64.77 0)
			(effects
				(font
					(size 1.27 1.27)
					(thickness 0.15)
				)
				(justify left bottom)
				(hide yes)
			)
		)
		(pin "1"
		)
		(instances
			(project "OCuLink to 10GbE adapter"
				(path ""
					(reference "#PWR0119")
					(unit 1)
				)
			)
		)
	)
	(symbol
		(lib_id "antmicroCapacitors0402:C_1u_25V_0402")
		(at 344.17 113.03 90)
		(unit 1)
		(exclude_from_sim no)
		(in_bom yes)
		(on_board yes)
		(dnp no)
		(property "Reference" "C134"
			(at 346.202 109.22 90)
			(effects
				(font
					(size 1.27 1.27)
					(thickness 0.15)
				)
				(justify right)
			)
		)
		(property "Value" "C_1u_25V_0402"
			(at 354.33 92.71 0)
			(effects
				(font
					(size 1.27 1.27)
					(thickness 0.15)
				)
				(justify left bottom)
				(hide yes)
			)
		)
		(property "Footprint" "antmicro-footprints:C_0402_1005Metric"
			(at 356.87 92.71 0)
			(effects
				(font
					(size 1.27 1.27)
					(thickness 0.15)
				)
				(justify left bottom)
				(hide yes)
			)
		)
		(property "Datasheet" "https://www.murata.com/products/productdetail?partno=GRM155R61E105KE11%23"
			(at 359.41 92.71 0)
			(effects
				(font
					(size 1.27 1.27)
					(thickness 0.15)
				)
				(justify left bottom)
				(hide yes)
			)
		)
		(property "Description" "SMD Multilayer Ceramic Capacitor, 1 µF, 25 V, 0402 [1005 Metric], ± 10%, X5R, GRM Series"
			(at 344.17 113.03 0)
			(effects
				(font
					(size 1.27 1.27)
				)
				(hide yes)
			)
		)
		(property "MPN" "GRM155R61E105KE11J"
			(at 361.95 92.71 0)
			(effects
				(font
					(size 1.27 1.27)
					(thickness 0.15)
				)
				(justify left bottom)
				(hide yes)
			)
		)
		(property "Manufacturer" "Murata"
			(at 364.49 92.71 0)
			(effects
				(font
					(size 1.27 1.27)
					(thickness 0.15)
				)
				(justify left bottom)
				(hide yes)
			)
		)
		(property "License" "Apache-2.0"
			(at 367.03 92.71 0)
			(effects
				(font
					(size 1.27 1.27)
					(thickness 0.15)
				)
				(justify left bottom)
				(hide yes)
			)
		)
		(property "Author" "Antmicro"
			(at 369.57 92.71 0)
			(effects
				(font
					(size 1.27 1.27)
					(thickness 0.15)
				)
				(justify left bottom)
				(hide yes)
			)
		)
		(property "Val" "1u"
			(at 346.202 111.76 90)
			(effects
				(font
					(size 1.27 1.27)
					(thickness 0.15)
				)
				(justify right)
			)
		)
		(property "Voltage" "25V"
			(at 372.11 92.71 0)
			(effects
				(font
					(size 1.27 1.27)
				)
				(justify left bottom)
				(hide yes)
			)
		)
		(property "Dielectric" "X5R"
			(at 374.65 92.71 0)
			(effects
				(font
					(size 1.27 1.27)
				)
				(justify left bottom)
				(hide yes)
			)
		)
		(pin "2"
		)
		(pin "1"
		)
		(instances
			(project "OCuLink to 10GbE adapter"
				(path ""
					(reference "C134")
					(unit 1)
				)
			)
		)
	)
	(symbol
		(lib_id "antmicroCapacitors0402:C_1u_25V_0402")
		(at 299.72 52.07 90)
		(unit 1)
		(exclude_from_sim no)
		(in_bom yes)
		(on_board yes)
		(dnp no)
		(property "Reference" "C87"
			(at 301.752 48.26 90)
			(effects
				(font
					(size 1.27 1.27)
					(thickness 0.15)
				)
				(justify right)
			)
		)
		(property "Value" "C_1u_25V_0402"
			(at 309.88 31.75 0)
			(effects
				(font
					(size 1.27 1.27)
					(thickness 0.15)
				)
				(justify left bottom)
				(hide yes)
			)
		)
		(property "Footprint" "antmicro-footprints:C_0402_1005Metric"
			(at 312.42 31.75 0)
			(effects
				(font
					(size 1.27 1.27)
					(thickness 0.15)
				)
				(justify left bottom)
				(hide yes)
			)
		)
		(property "Datasheet" "https://www.murata.com/products/productdetail?partno=GRM155R61E105KE11%23"
			(at 314.96 31.75 0)
			(effects
				(font
					(size 1.27 1.27)
					(thickness 0.15)
				)
				(justify left bottom)
				(hide yes)
			)
		)
		(property "Description" "SMD Multilayer Ceramic Capacitor, 1 µF, 25 V, 0402 [1005 Metric], ± 10%, X5R, GRM Series"
			(at 299.72 52.07 0)
			(effects
				(font
					(size 1.27 1.27)
				)
				(hide yes)
			)
		)
		(property "MPN" "GRM155R61E105KE11J"
			(at 317.5 31.75 0)
			(effects
				(font
					(size 1.27 1.27)
					(thickness 0.15)
				)
				(justify left bottom)
				(hide yes)
			)
		)
		(property "Manufacturer" "Murata"
			(at 320.04 31.75 0)
			(effects
				(font
					(size 1.27 1.27)
					(thickness 0.15)
				)
				(justify left bottom)
				(hide yes)
			)
		)
		(property "License" "Apache-2.0"
			(at 322.58 31.75 0)
			(effects
				(font
					(size 1.27 1.27)
					(thickness 0.15)
				)
				(justify left bottom)
				(hide yes)
			)
		)
		(property "Author" "Antmicro"
			(at 325.12 31.75 0)
			(effects
				(font
					(size 1.27 1.27)
					(thickness 0.15)
				)
				(justify left bottom)
				(hide yes)
			)
		)
		(property "Val" "1u"
			(at 301.752 50.8 90)
			(effects
				(font
					(size 1.27 1.27)
					(thickness 0.15)
				)
				(justify right)
			)
		)
		(property "Voltage" "25V"
			(at 327.66 31.75 0)
			(effects
				(font
					(size 1.27 1.27)
				)
				(justify left bottom)
				(hide yes)
			)
		)
		(property "Dielectric" "X5R"
			(at 330.2 31.75 0)
			(effects
				(font
					(size 1.27 1.27)
				)
				(justify left bottom)
				(hide yes)
			)
		)
		(pin "2"
		)
		(pin "1"
		)
		(instances
			(project "OCuLink to 10GbE adapter"
				(path ""
					(reference "C87")
					(unit 1)
				)
			)
		)
	)
	(symbol
		(lib_id "antmicropower:+1V0")
		(at 21.59 143.51 0)
		(unit 1)
		(exclude_from_sim no)
		(in_bom yes)
		(on_board yes)
		(dnp no)
		(property "Reference" "#PWR0205"
			(at 21.59 147.32 0)
			(effects
				(font
					(size 1.27 1.27)
				)
				(hide yes)
			)
		)
		(property "Value" "+1V0"
			(at 21.59 139.7 0)
			(effects
				(font
					(size 1.27 1.27)
				)
			)
		)
		(property "Footprint" ""
			(at 21.59 143.51 0)
			(effects
				(font
					(size 1.27 1.27)
				)
				(hide yes)
			)
		)
		(property "Datasheet" ""
			(at 21.59 143.51 0)
			(effects
				(font
					(size 1.27 1.27)
				)
				(hide yes)
			)
		)
		(property "Description" ""
			(at 21.59 143.51 0)
			(effects
				(font
					(size 1.27 1.27)
				)
				(hide yes)
			)
		)
		(pin "1"
		)
		(instances
			(project ""
				(path ""
					(reference "#PWR0205")
					(unit 1)
				)
			)
		)
	)
	(symbol
		(lib_id "antmicroCapacitors0603:C_22u_16V_0603")
		(at 361.95 130.81 90)
		(unit 1)
		(exclude_from_sim no)
		(in_bom yes)
		(on_board yes)
		(dnp no)
		(fields_autoplaced yes)
		(property "Reference" "C152"
			(at 364.49 126.9936 90)
			(effects
				(font
					(size 1.27 1.27)
					(thickness 0.15)
				)
				(justify right)
			)
		)
		(property "Value" "C_22u_16V_0603"
			(at 372.11 110.49 0)
			(effects
				(font
					(size 1.27 1.27)
					(thickness 0.15)
				)
				(justify left bottom)
				(hide yes)
			)
		)
		(property "Footprint" "antmicro-footprints:C_0603_1608Metric_EIA"
			(at 374.65 110.49 0)
			(effects
				(font
					(size 1.27 1.27)
					(thickness 0.15)
				)
				(justify left bottom)
				(hide yes)
			)
		)
		(property "Datasheet" "https://product.samsungsem.com/mlcc/CL10A226MO7JZN.do"
			(at 377.19 110.49 0)
			(effects
				(font
					(size 1.27 1.27)
					(thickness 0.15)
				)
				(justify left bottom)
				(hide yes)
			)
		)
		(property "Description" "SMD Multilayer Ceramic Capacitor"
			(at 361.95 130.81 0)
			(effects
				(font
					(size 1.27 1.27)
				)
				(hide yes)
			)
		)
		(property "MPN" "CL10A226MO7JZNC"
			(at 379.73 110.49 0)
			(effects
				(font
					(size 1.27 1.27)
					(thickness 0.15)
				)
				(justify left bottom)
				(hide yes)
			)
		)
		(property "Manufacturer" "Samsung Electro-Mechanics"
			(at 382.27 110.49 0)
			(effects
				(font
					(size 1.27 1.27)
					(thickness 0.15)
				)
				(justify left bottom)
				(hide yes)
			)
		)
		(property "License" "Apache-2.0"
			(at 384.81 110.49 0)
			(effects
				(font
					(size 1.27 1.27)
					(thickness 0.15)
				)
				(justify left bottom)
				(hide yes)
			)
		)
		(property "Author" "Antmicro"
			(at 387.35 110.49 0)
			(effects
				(font
					(size 1.27 1.27)
					(thickness 0.15)
				)
				(justify left bottom)
				(hide yes)
			)
		)
		(property "Val" "22u"
			(at 364.49 129.5336 90)
			(effects
				(font
					(size 1.27 1.27)
					(thickness 0.15)
				)
				(justify right)
			)
		)
		(property "Voltage" "16V"
			(at 389.89 110.49 0)
			(effects
				(font
					(size 1.27 1.27)
				)
				(justify left bottom)
				(hide yes)
			)
		)
		(property "Dielectric" ""
			(at 392.43 110.49 0)
			(effects
				(font
					(size 1.27 1.27)
				)
				(justify left bottom)
				(hide yes)
			)
		)
		(pin "1"
		)
		(pin "2"
		)
		(instances
			(project "OCuLink to 10GbE adapter"
				(path ""
					(reference "C152")
					(unit 1)
				)
			)
		)
	)
	(symbol
		(lib_id "antmicroCapacitors0402:C_1u_25V_0402")
		(at 97.79 207.01 90)
		(unit 1)
		(exclude_from_sim no)
		(in_bom yes)
		(on_board yes)
		(dnp no)
		(property "Reference" "C182"
			(at 99.822 203.2 90)
			(effects
				(font
					(size 1.27 1.27)
					(thickness 0.15)
				)
				(justify right)
			)
		)
		(property "Value" "C_1u_25V_0402"
			(at 107.95 186.69 0)
			(effects
				(font
					(size 1.27 1.27)
					(thickness 0.15)
				)
				(justify left bottom)
				(hide yes)
			)
		)
		(property "Footprint" "antmicro-footprints:C_0402_1005Metric"
			(at 110.49 186.69 0)
			(effects
				(font
					(size 1.27 1.27)
					(thickness 0.15)
				)
				(justify left bottom)
				(hide yes)
			)
		)
		(property "Datasheet" "https://www.murata.com/products/productdetail?partno=GRM155R61E105KE11%23"
			(at 113.03 186.69 0)
			(effects
				(font
					(size 1.27 1.27)
					(thickness 0.15)
				)
				(justify left bottom)
				(hide yes)
			)
		)
		(property "Description" "SMD Multilayer Ceramic Capacitor, 1 µF, 25 V, 0402 [1005 Metric], ± 10%, X5R, GRM Series"
			(at 97.79 207.01 0)
			(effects
				(font
					(size 1.27 1.27)
				)
				(hide yes)
			)
		)
		(property "MPN" "GRM155R61E105KE11J"
			(at 115.57 186.69 0)
			(effects
				(font
					(size 1.27 1.27)
					(thickness 0.15)
				)
				(justify left bottom)
				(hide yes)
			)
		)
		(property "Manufacturer" "Murata"
			(at 118.11 186.69 0)
			(effects
				(font
					(size 1.27 1.27)
					(thickness 0.15)
				)
				(justify left bottom)
				(hide yes)
			)
		)
		(property "License" "Apache-2.0"
			(at 120.65 186.69 0)
			(effects
				(font
					(size 1.27 1.27)
					(thickness 0.15)
				)
				(justify left bottom)
				(hide yes)
			)
		)
		(property "Author" "Antmicro"
			(at 123.19 186.69 0)
			(effects
				(font
					(size 1.27 1.27)
					(thickness 0.15)
				)
				(justify left bottom)
				(hide yes)
			)
		)
		(property "Val" "1u"
			(at 99.822 205.74 90)
			(effects
				(font
					(size 1.27 1.27)
					(thickness 0.15)
				)
				(justify right)
			)
		)
		(property "Voltage" "25V"
			(at 125.73 186.69 0)
			(effects
				(font
					(size 1.27 1.27)
				)
				(justify left bottom)
				(hide yes)
			)
		)
		(property "Dielectric" "X5R"
			(at 128.27 186.69 0)
			(effects
				(font
					(size 1.27 1.27)
				)
				(justify left bottom)
				(hide yes)
			)
		)
		(pin "2"
		)
		(pin "1"
		)
		(instances
			(project "OCuLink to 10GbE adapter"
				(path ""
					(reference "C182")
					(unit 1)
				)
			)
		)
	)
	(symbol
		(lib_id "antmicroCapacitors0603:C_22u_16V_0603")
		(at 361.95 91.44 90)
		(unit 1)
		(exclude_from_sim no)
		(in_bom yes)
		(on_board yes)
		(dnp no)
		(fields_autoplaced yes)
		(property "Reference" "C123"
			(at 364.49 87.6236 90)
			(effects
				(font
					(size 1.27 1.27)
					(thickness 0.15)
				)
				(justify right)
			)
		)
		(property "Value" "C_22u_16V_0603"
			(at 372.11 71.12 0)
			(effects
				(font
					(size 1.27 1.27)
					(thickness 0.15)
				)
				(justify left bottom)
				(hide yes)
			)
		)
		(property "Footprint" "antmicro-footprints:C_0603_1608Metric_EIA"
			(at 374.65 71.12 0)
			(effects
				(font
					(size 1.27 1.27)
					(thickness 0.15)
				)
				(justify left bottom)
				(hide yes)
			)
		)
		(property "Datasheet" "https://product.samsungsem.com/mlcc/CL10A226MO7JZN.do"
			(at 377.19 71.12 0)
			(effects
				(font
					(size 1.27 1.27)
					(thickness 0.15)
				)
				(justify left bottom)
				(hide yes)
			)
		)
		(property "Description" "SMD Multilayer Ceramic Capacitor"
			(at 361.95 91.44 0)
			(effects
				(font
					(size 1.27 1.27)
				)
				(hide yes)
			)
		)
		(property "MPN" "CL10A226MO7JZNC"
			(at 379.73 71.12 0)
			(effects
				(font
					(size 1.27 1.27)
					(thickness 0.15)
				)
				(justify left bottom)
				(hide yes)
			)
		)
		(property "Manufacturer" "Samsung Electro-Mechanics"
			(at 382.27 71.12 0)
			(effects
				(font
					(size 1.27 1.27)
					(thickness 0.15)
				)
				(justify left bottom)
				(hide yes)
			)
		)
		(property "License" "Apache-2.0"
			(at 384.81 71.12 0)
			(effects
				(font
					(size 1.27 1.27)
					(thickness 0.15)
				)
				(justify left bottom)
				(hide yes)
			)
		)
		(property "Author" "Antmicro"
			(at 387.35 71.12 0)
			(effects
				(font
					(size 1.27 1.27)
					(thickness 0.15)
				)
				(justify left bottom)
				(hide yes)
			)
		)
		(property "Val" "22u"
			(at 364.49 90.1636 90)
			(effects
				(font
					(size 1.27 1.27)
					(thickness 0.15)
				)
				(justify right)
			)
		)
		(property "Voltage" "16V"
			(at 389.89 71.12 0)
			(effects
				(font
					(size 1.27 1.27)
				)
				(justify left bottom)
				(hide yes)
			)
		)
		(property "Dielectric" ""
			(at 392.43 71.12 0)
			(effects
				(font
					(size 1.27 1.27)
				)
				(justify left bottom)
				(hide yes)
			)
		)
		(pin "1"
		)
		(pin "2"
		)
		(instances
			(project "OCuLink to 10GbE adapter"
				(path ""
					(reference "C123")
					(unit 1)
				)
			)
		)
	)
	(symbol
		(lib_id "antmicroCapacitors0402:C_1u_25V_0402")
		(at 97.79 153.67 90)
		(unit 1)
		(exclude_from_sim no)
		(in_bom yes)
		(on_board yes)
		(dnp no)
		(property "Reference" "C167"
			(at 99.822 149.86 90)
			(effects
				(font
					(size 1.27 1.27)
					(thickness 0.15)
				)
				(justify right)
			)
		)
		(property "Value" "C_1u_25V_0402"
			(at 107.95 133.35 0)
			(effects
				(font
					(size 1.27 1.27)
					(thickness 0.15)
				)
				(justify left bottom)
				(hide yes)
			)
		)
		(property "Footprint" "antmicro-footprints:C_0402_1005Metric"
			(at 110.49 133.35 0)
			(effects
				(font
					(size 1.27 1.27)
					(thickness 0.15)
				)
				(justify left bottom)
				(hide yes)
			)
		)
		(property "Datasheet" "https://www.murata.com/products/productdetail?partno=GRM155R61E105KE11%23"
			(at 113.03 133.35 0)
			(effects
				(font
					(size 1.27 1.27)
					(thickness 0.15)
				)
				(justify left bottom)
				(hide yes)
			)
		)
		(property "Description" "SMD Multilayer Ceramic Capacitor, 1 µF, 25 V, 0402 [1005 Metric], ± 10%, X5R, GRM Series"
			(at 97.79 153.67 0)
			(effects
				(font
					(size 1.27 1.27)
				)
				(hide yes)
			)
		)
		(property "MPN" "GRM155R61E105KE11J"
			(at 115.57 133.35 0)
			(effects
				(font
					(size 1.27 1.27)
					(thickness 0.15)
				)
				(justify left bottom)
				(hide yes)
			)
		)
		(property "Manufacturer" "Murata"
			(at 118.11 133.35 0)
			(effects
				(font
					(size 1.27 1.27)
					(thickness 0.15)
				)
				(justify left bottom)
				(hide yes)
			)
		)
		(property "License" "Apache-2.0"
			(at 120.65 133.35 0)
			(effects
				(font
					(size 1.27 1.27)
					(thickness 0.15)
				)
				(justify left bottom)
				(hide yes)
			)
		)
		(property "Author" "Antmicro"
			(at 123.19 133.35 0)
			(effects
				(font
					(size 1.27 1.27)
					(thickness 0.15)
				)
				(justify left bottom)
				(hide yes)
			)
		)
		(property "Val" "1u"
			(at 99.822 152.4 90)
			(effects
				(font
					(size 1.27 1.27)
					(thickness 0.15)
				)
				(justify right)
			)
		)
		(property "Voltage" "25V"
			(at 125.73 133.35 0)
			(effects
				(font
					(size 1.27 1.27)
				)
				(justify left bottom)
				(hide yes)
			)
		)
		(property "Dielectric" "X5R"
			(at 128.27 133.35 0)
			(effects
				(font
					(size 1.27 1.27)
				)
				(justify left bottom)
				(hide yes)
			)
		)
		(pin "2"
		)
		(pin "1"
		)
		(instances
			(project "OCuLink to 10GbE adapter"
				(path ""
					(reference "C167")
					(unit 1)
				)
			)
		)
	)
	(symbol
		(lib_id "antmicropower:GND")
		(at 115.57 129.54 0)
		(unit 1)
		(exclude_from_sim no)
		(in_bom yes)
		(on_board yes)
		(dnp no)
		(property "Reference" "#PWR0194"
			(at 124.46 132.08 0)
			(effects
				(font
					(size 1.27 1.27)
					(thickness 0.15)
				)
				(justify left bottom)
				(hide yes)
			)
		)
		(property "Value" "GND"
			(at 115.57 133.35 0)
			(effects
				(font
					(size 1.27 1.27)
					(thickness 0.15)
				)
			)
		)
		(property "Footprint" ""
			(at 124.46 137.16 0)
			(effects
				(font
					(size 1.27 1.27)
					(thickness 0.15)
				)
				(justify left bottom)
				(hide yes)
			)
		)
		(property "Datasheet" ""
			(at 124.46 142.24 0)
			(effects
				(font
					(size 1.27 1.27)
					(thickness 0.15)
				)
				(justify left bottom)
				(hide yes)
			)
		)
		(property "Description" ""
			(at 115.57 129.54 0)
			(effects
				(font
					(size 1.27 1.27)
				)
				(hide yes)
			)
		)
		(property "Author" "Antmicro"
			(at 124.46 137.16 0)
			(effects
				(font
					(size 1.27 1.27)
					(thickness 0.15)
				)
				(justify left bottom)
				(hide yes)
			)
		)
		(property "License" "Apache-2.0"
			(at 124.46 139.7 0)
			(effects
				(font
					(size 1.27 1.27)
					(thickness 0.15)
				)
				(justify left bottom)
				(hide yes)
			)
		)
		(pin "1"
		)
		(instances
			(project "OCuLink to 10GbE adapter"
				(path ""
					(reference "#PWR0194")
					(unit 1)
				)
			)
		)
	)
	(symbol
		(lib_id "antmicropower:VDD")
		(at 176.53 78.74 0)
		(unit 1)
		(exclude_from_sim no)
		(in_bom yes)
		(on_board yes)
		(dnp no)
		(property "Reference" "#PWR0155"
			(at 176.53 82.55 0)
			(effects
				(font
					(size 1.27 1.27)
				)
				(hide yes)
			)
		)
		(property "Value" "P0_AVDDL"
			(at 176.53 74.93 0)
			(effects
				(font
					(size 1.27 1.27)
				)
			)
		)
		(property "Footprint" ""
			(at 176.53 78.74 0)
			(effects
				(font
					(size 1.27 1.27)
				)
				(hide yes)
			)
		)
		(property "Datasheet" ""
			(at 176.53 78.74 0)
			(effects
				(font
					(size 1.27 1.27)
				)
				(hide yes)
			)
		)
		(property "Description" ""
			(at 176.53 78.74 0)
			(effects
				(font
					(size 1.27 1.27)
				)
				(hide yes)
			)
		)
		(pin "1"
		)
		(instances
			(project "OCuLink to 10GbE adapter"
				(path ""
					(reference "#PWR0155")
					(unit 1)
				)
			)
		)
	)
	(symbol
		(lib_id "antmicroCapacitors0402:C_1u_25V_0402")
		(at 106.68 153.67 90)
		(unit 1)
		(exclude_from_sim no)
		(in_bom yes)
		(on_board yes)
		(dnp no)
		(property "Reference" "C168"
			(at 108.712 149.86 90)
			(effects
				(font
					(size 1.27 1.27)
					(thickness 0.15)
				)
				(justify right)
			)
		)
		(property "Value" "C_1u_25V_0402"
			(at 116.84 133.35 0)
			(effects
				(font
					(size 1.27 1.27)
					(thickness 0.15)
				)
				(justify left bottom)
				(hide yes)
			)
		)
		(property "Footprint" "antmicro-footprints:C_0402_1005Metric"
			(at 119.38 133.35 0)
			(effects
				(font
					(size 1.27 1.27)
					(thickness 0.15)
				)
				(justify left bottom)
				(hide yes)
			)
		)
		(property "Datasheet" "https://www.murata.com/products/productdetail?partno=GRM155R61E105KE11%23"
			(at 121.92 133.35 0)
			(effects
				(font
					(size 1.27 1.27)
					(thickness 0.15)
				)
				(justify left bottom)
				(hide yes)
			)
		)
		(property "Description" "SMD Multilayer Ceramic Capacitor, 1 µF, 25 V, 0402 [1005 Metric], ± 10%, X5R, GRM Series"
			(at 106.68 153.67 0)
			(effects
				(font
					(size 1.27 1.27)
				)
				(hide yes)
			)
		)
		(property "MPN" "GRM155R61E105KE11J"
			(at 124.46 133.35 0)
			(effects
				(font
					(size 1.27 1.27)
					(thickness 0.15)
				)
				(justify left bottom)
				(hide yes)
			)
		)
		(property "Manufacturer" "Murata"
			(at 127 133.35 0)
			(effects
				(font
					(size 1.27 1.27)
					(thickness 0.15)
				)
				(justify left bottom)
				(hide yes)
			)
		)
		(property "License" "Apache-2.0"
			(at 129.54 133.35 0)
			(effects
				(font
					(size 1.27 1.27)
					(thickness 0.15)
				)
				(justify left bottom)
				(hide yes)
			)
		)
		(property "Author" "Antmicro"
			(at 132.08 133.35 0)
			(effects
				(font
					(size 1.27 1.27)
					(thickness 0.15)
				)
				(justify left bottom)
				(hide yes)
			)
		)
		(property "Val" "1u"
			(at 108.712 152.4 90)
			(effects
				(font
					(size 1.27 1.27)
					(thickness 0.15)
				)
				(justify right)
			)
		)
		(property "Voltage" "25V"
			(at 134.62 133.35 0)
			(effects
				(font
					(size 1.27 1.27)
				)
				(justify left bottom)
				(hide yes)
			)
		)
		(property "Dielectric" "X5R"
			(at 137.16 133.35 0)
			(effects
				(font
					(size 1.27 1.27)
				)
				(justify left bottom)
				(hide yes)
			)
		)
		(pin "2"
		)
		(pin "1"
		)
		(instances
			(project "OCuLink to 10GbE adapter"
				(path ""
					(reference "C168")
					(unit 1)
				)
			)
		)
	)
	(symbol
		(lib_id "antmicroFerriteBeadsandChips:FB_470Z_1A_Murata-BLM18PG_0603")
		(at 45.72 92.71 0)
		(unit 1)
		(exclude_from_sim no)
		(in_bom yes)
		(on_board yes)
		(dnp no)
		(fields_autoplaced yes)
		(property "Reference" "FB3"
			(at 48.2219 86.36 0)
			(effects
				(font
					(size 1.27 1.27)
					(thickness 0.15)
				)
			)
		)
		(property "Value" "FB_470Z_1A_Murata-BLM18PG_0603"
			(at 59.69 95.25 0)
			(effects
				(font
					(size 1.27 1.27)
					(thickness 0.15)
				)
				(justify left bottom)
				(hide yes)
			)
		)
		(property "Footprint" "antmicro-footprints:FB_0603_1608Metric"
			(at 59.69 100.33 0)
			(effects
				(font
					(size 1.27 1.27)
					(thickness 0.15)
				)
				(justify left bottom)
				(hide yes)
			)
		)
		(property "Datasheet" "https://www.murata.com/en-us/products/productdata/8796738650142/ENFA0003.pdf"
			(at 59.69 102.87 0)
			(effects
				(font
					(size 1.27 1.27)
					(thickness 0.15)
				)
				(justify left bottom)
				(hide yes)
			)
		)
		(property "Description" "Ferrite Bead, 0603 [1608 Metric], 470 ohm, 1 A, BLM18P, 0.2 ohm, ± 25%, DC power line"
			(at 45.72 92.71 0)
			(effects
				(font
					(size 1.27 1.27)
				)
				(hide yes)
			)
		)
		(property "Val" "470Z/1A"
			(at 48.2219 88.9 0)
			(effects
				(font
					(size 1.27 1.27)
				)
			)
		)
		(property "MPN" "BLM18PG471SN1D"
			(at 59.69 105.41 0)
			(effects
				(font
					(size 1.27 1.27)
					(thickness 0.15)
				)
				(justify left bottom)
				(hide yes)
			)
		)
		(property "Manufacturer" "Murata"
			(at 59.69 107.95 0)
			(effects
				(font
					(size 1.27 1.27)
					(thickness 0.15)
				)
				(justify left bottom)
				(hide yes)
			)
		)
		(property "Current" ""
			(at 66.04 115.57 0)
			(effects
				(font
					(size 1.27 1.27)
					(thickness 0.15)
				)
				(justify left bottom)
				(hide yes)
			)
		)
		(property "Author" "Antmicro"
			(at 59.69 110.49 0)
			(effects
				(font
					(size 1.27 1.27)
					(thickness 0.15)
				)
				(justify left bottom)
				(hide yes)
			)
		)
		(property "License" "Apache-2.0"
			(at 59.69 113.03 0)
			(effects
				(font
					(size 1.27 1.27)
					(thickness 0.15)
				)
				(justify left bottom)
				(hide yes)
			)
		)
		(pin "2"
		)
		(pin "1"
		)
		(instances
			(project "OCuLink to 10GbE adapter"
				(path ""
					(reference "FB3")
					(unit 1)
				)
			)
		)
	)
	(symbol
		(lib_id "antmicropower:GND")
		(at 80.01 129.54 0)
		(unit 1)
		(exclude_from_sim no)
		(in_bom yes)
		(on_board yes)
		(dnp no)
		(property "Reference" "#PWR0190"
			(at 88.9 132.08 0)
			(effects
				(font
					(size 1.27 1.27)
					(thickness 0.15)
				)
				(justify left bottom)
				(hide yes)
			)
		)
		(property "Value" "GND"
			(at 80.01 133.35 0)
			(effects
				(font
					(size 1.27 1.27)
					(thickness 0.15)
				)
			)
		)
		(property "Footprint" ""
			(at 88.9 137.16 0)
			(effects
				(font
					(size 1.27 1.27)
					(thickness 0.15)
				)
				(justify left bottom)
				(hide yes)
			)
		)
		(property "Datasheet" ""
			(at 88.9 142.24 0)
			(effects
				(font
					(size 1.27 1.27)
					(thickness 0.15)
				)
				(justify left bottom)
				(hide yes)
			)
		)
		(property "Description" ""
			(at 80.01 129.54 0)
			(effects
				(font
					(size 1.27 1.27)
				)
				(hide yes)
			)
		)
		(property "Author" "Antmicro"
			(at 88.9 137.16 0)
			(effects
				(font
					(size 1.27 1.27)
					(thickness 0.15)
				)
				(justify left bottom)
				(hide yes)
			)
		)
		(property "License" "Apache-2.0"
			(at 88.9 139.7 0)
			(effects
				(font
					(size 1.27 1.27)
					(thickness 0.15)
				)
				(justify left bottom)
				(hide yes)
			)
		)
		(pin "1"
		)
		(instances
			(project "OCuLink to 10GbE adapter"
				(path ""
					(reference "#PWR0190")
					(unit 1)
				)
			)
		)
	)
	(symbol
		(lib_id "antmicroCapacitors0603:C_22u_16V_0603")
		(at 31.75 180.34 90)
		(unit 1)
		(exclude_from_sim no)
		(in_bom yes)
		(on_board yes)
		(dnp no)
		(property "Reference" "C170"
			(at 33.782 176.53 90)
			(effects
				(font
					(size 1.27 1.27)
					(thickness 0.15)
				)
				(justify right)
			)
		)
		(property "Value" "C_22u_16V_0603"
			(at 41.91 160.02 0)
			(effects
				(font
					(size 1.27 1.27)
					(thickness 0.15)
				)
				(justify left bottom)
				(hide yes)
			)
		)
		(property "Footprint" "antmicro-footprints:C_0603_1608Metric_EIA"
			(at 44.45 160.02 0)
			(effects
				(font
					(size 1.27 1.27)
					(thickness 0.15)
				)
				(justify left bottom)
				(hide yes)
			)
		)
		(property "Datasheet" "https://product.samsungsem.com/mlcc/CL10A226MO7JZN.do"
			(at 46.99 160.02 0)
			(effects
				(font
					(size 1.27 1.27)
					(thickness 0.15)
				)
				(justify left bottom)
				(hide yes)
			)
		)
		(property "Description" "SMD Multilayer Ceramic Capacitor"
			(at 31.75 180.34 0)
			(effects
				(font
					(size 1.27 1.27)
				)
				(hide yes)
			)
		)
		(property "MPN" "CL10A226MO7JZNC"
			(at 49.53 160.02 0)
			(effects
				(font
					(size 1.27 1.27)
					(thickness 0.15)
				)
				(justify left bottom)
				(hide yes)
			)
		)
		(property "Manufacturer" "Samsung Electro-Mechanics"
			(at 52.07 160.02 0)
			(effects
				(font
					(size 1.27 1.27)
					(thickness 0.15)
				)
				(justify left bottom)
				(hide yes)
			)
		)
		(property "License" "Apache-2.0"
			(at 54.61 160.02 0)
			(effects
				(font
					(size 1.27 1.27)
					(thickness 0.15)
				)
				(justify left bottom)
				(hide yes)
			)
		)
		(property "Author" "Antmicro"
			(at 57.15 160.02 0)
			(effects
				(font
					(size 1.27 1.27)
					(thickness 0.15)
				)
				(justify left bottom)
				(hide yes)
			)
		)
		(property "Val" "22u"
			(at 33.782 179.07 90)
			(effects
				(font
					(size 1.27 1.27)
					(thickness 0.15)
				)
				(justify right)
			)
		)
		(property "Voltage" "16V"
			(at 59.69 160.02 0)
			(effects
				(font
					(size 1.27 1.27)
				)
				(justify left bottom)
				(hide yes)
			)
		)
		(property "Dielectric" ""
			(at 62.23 160.02 0)
			(effects
				(font
					(size 1.27 1.27)
				)
				(justify left bottom)
				(hide yes)
			)
		)
		(pin "1"
		)
		(pin "2"
		)
		(instances
			(project "OCuLink to 10GbE adapter"
				(path ""
					(reference "C170")
					(unit 1)
				)
			)
		)
	)
	(symbol
		(lib_id "antmicropower:GND")
		(at 335.28 93.98 0)
		(unit 1)
		(exclude_from_sim no)
		(in_bom yes)
		(on_board yes)
		(dnp no)
		(property "Reference" "#PWR0168"
			(at 344.17 96.52 0)
			(effects
				(font
					(size 1.27 1.27)
					(thickness 0.15)
				)
				(justify left bottom)
				(hide yes)
			)
		)
		(property "Value" "GND"
			(at 335.28 97.79 0)
			(effects
				(font
					(size 1.27 1.27)
					(thickness 0.15)
				)
			)
		)
		(property "Footprint" ""
			(at 344.17 101.6 0)
			(effects
				(font
					(size 1.27 1.27)
					(thickness 0.15)
				)
				(justify left bottom)
				(hide yes)
			)
		)
		(property "Datasheet" ""
			(at 344.17 106.68 0)
			(effects
				(font
					(size 1.27 1.27)
					(thickness 0.15)
				)
				(justify left bottom)
				(hide yes)
			)
		)
		(property "Description" ""
			(at 335.28 93.98 0)
			(effects
				(font
					(size 1.27 1.27)
				)
				(hide yes)
			)
		)
		(property "Author" "Antmicro"
			(at 344.17 101.6 0)
			(effects
				(font
					(size 1.27 1.27)
					(thickness 0.15)
				)
				(justify left bottom)
				(hide yes)
			)
		)
		(property "License" "Apache-2.0"
			(at 344.17 104.14 0)
			(effects
				(font
					(size 1.27 1.27)
					(thickness 0.15)
				)
				(justify left bottom)
				(hide yes)
			)
		)
		(pin "1"
		)
		(instances
			(project "OCuLink to 10GbE adapter"
				(path ""
					(reference "#PWR0168")
					(unit 1)
				)
			)
		)
	)
	(symbol
		(lib_id "antmicroCapacitors0402:C_1u_25V_0402")
		(at 344.17 73.66 90)
		(unit 1)
		(exclude_from_sim no)
		(in_bom yes)
		(on_board yes)
		(dnp no)
		(property "Reference" "C110"
			(at 346.202 69.85 90)
			(effects
				(font
					(size 1.27 1.27)
					(thickness 0.15)
				)
				(justify right)
			)
		)
		(property "Value" "C_1u_25V_0402"
			(at 354.33 53.34 0)
			(effects
				(font
					(size 1.27 1.27)
					(thickness 0.15)
				)
				(justify left bottom)
				(hide yes)
			)
		)
		(property "Footprint" "antmicro-footprints:C_0402_1005Metric"
			(at 356.87 53.34 0)
			(effects
				(font
					(size 1.27 1.27)
					(thickness 0.15)
				)
				(justify left bottom)
				(hide yes)
			)
		)
		(property "Datasheet" "https://www.murata.com/products/productdetail?partno=GRM155R61E105KE11%23"
			(at 359.41 53.34 0)
			(effects
				(font
					(size 1.27 1.27)
					(thickness 0.15)
				)
				(justify left bottom)
				(hide yes)
			)
		)
		(property "Description" "SMD Multilayer Ceramic Capacitor, 1 µF, 25 V, 0402 [1005 Metric], ± 10%, X5R, GRM Series"
			(at 344.17 73.66 0)
			(effects
				(font
					(size 1.27 1.27)
				)
				(hide yes)
			)
		)
		(property "MPN" "GRM155R61E105KE11J"
			(at 361.95 53.34 0)
			(effects
				(font
					(size 1.27 1.27)
					(thickness 0.15)
				)
				(justify left bottom)
				(hide yes)
			)
		)
		(property "Manufacturer" "Murata"
			(at 364.49 53.34 0)
			(effects
				(font
					(size 1.27 1.27)
					(thickness 0.15)
				)
				(justify left bottom)
				(hide yes)
			)
		)
		(property "License" "Apache-2.0"
			(at 367.03 53.34 0)
			(effects
				(font
					(size 1.27 1.27)
					(thickness 0.15)
				)
				(justify left bottom)
				(hide yes)
			)
		)
		(property "Author" "Antmicro"
			(at 369.57 53.34 0)
			(effects
				(font
					(size 1.27 1.27)
					(thickness 0.15)
				)
				(justify left bottom)
				(hide yes)
			)
		)
		(property "Val" "1u"
			(at 346.202 72.39 90)
			(effects
				(font
					(size 1.27 1.27)
					(thickness 0.15)
				)
				(justify right)
			)
		)
		(property "Voltage" "25V"
			(at 372.11 53.34 0)
			(effects
				(font
					(size 1.27 1.27)
				)
				(justify left bottom)
				(hide yes)
			)
		)
		(property "Dielectric" "X5R"
			(at 374.65 53.34 0)
			(effects
				(font
					(size 1.27 1.27)
				)
				(justify left bottom)
				(hide yes)
			)
		)
		(pin "2"
		)
		(pin "1"
		)
		(instances
			(project "OCuLink to 10GbE adapter"
				(path ""
					(reference "C110")
					(unit 1)
				)
			)
		)
	)
	(symbol
		(lib_id "antmicropower:GND")
		(at 379.73 93.98 0)
		(unit 1)
		(exclude_from_sim no)
		(in_bom yes)
		(on_board yes)
		(dnp no)
		(property "Reference" "#PWR0172"
			(at 388.62 96.52 0)
			(effects
				(font
					(size 1.27 1.27)
					(thickness 0.15)
				)
				(justify left bottom)
				(hide yes)
			)
		)
		(property "Value" "GND"
			(at 379.73 97.79 0)
			(effects
				(font
					(size 1.27 1.27)
					(thickness 0.15)
				)
			)
		)
		(property "Footprint" ""
			(at 388.62 101.6 0)
			(effects
				(font
					(size 1.27 1.27)
					(thickness 0.15)
				)
				(justify left bottom)
				(hide yes)
			)
		)
		(property "Datasheet" ""
			(at 388.62 106.68 0)
			(effects
				(font
					(size 1.27 1.27)
					(thickness 0.15)
				)
				(justify left bottom)
				(hide yes)
			)
		)
		(property "Description" ""
			(at 379.73 93.98 0)
			(effects
				(font
					(size 1.27 1.27)
				)
				(hide yes)
			)
		)
		(property "Author" "Antmicro"
			(at 388.62 101.6 0)
			(effects
				(font
					(size 1.27 1.27)
					(thickness 0.15)
				)
				(justify left bottom)
				(hide yes)
			)
		)
		(property "License" "Apache-2.0"
			(at 388.62 104.14 0)
			(effects
				(font
					(size 1.27 1.27)
					(thickness 0.15)
				)
				(justify left bottom)
				(hide yes)
			)
		)
		(pin "1"
		)
		(instances
			(project "OCuLink to 10GbE adapter"
				(path ""
					(reference "#PWR0172")
					(unit 1)
				)
			)
		)
	)
	(symbol
		(lib_id "antmicropower:VCC")
		(at 270.51 78.74 0)
		(unit 1)
		(exclude_from_sim no)
		(in_bom yes)
		(on_board yes)
		(dnp no)
		(property "Reference" "#PWR0160"
			(at 270.51 82.55 0)
			(effects
				(font
					(size 1.27 1.27)
				)
				(hide yes)
			)
		)
		(property "Value" "VCCA"
			(at 270.51 74.93 0)
			(effects
				(font
					(size 1.27 1.27)
				)
			)
		)
		(property "Footprint" ""
			(at 270.51 78.74 0)
			(effects
				(font
					(size 1.27 1.27)
				)
				(hide yes)
			)
		)
		(property "Datasheet" ""
			(at 270.51 78.74 0)
			(effects
				(font
					(size 1.27 1.27)
				)
				(hide yes)
			)
		)
		(property "Description" ""
			(at 270.51 78.74 0)
			(effects
				(font
					(size 1.27 1.27)
				)
				(hide yes)
			)
		)
		(pin "1"
		)
		(instances
			(project "OCuLink to 10GbE adapter"
				(path ""
					(reference "#PWR0160")
					(unit 1)
				)
			)
		)
	)
	(symbol
		(lib_id "antmicropower:GND")
		(at 97.79 209.55 0)
		(unit 1)
		(exclude_from_sim no)
		(in_bom yes)
		(on_board yes)
		(dnp no)
		(property "Reference" "#PWR0235"
			(at 106.68 212.09 0)
			(effects
				(font
					(size 1.27 1.27)
					(thickness 0.15)
				)
				(justify left bottom)
				(hide yes)
			)
		)
		(property "Value" "GND"
			(at 97.79 213.36 0)
			(effects
				(font
					(size 1.27 1.27)
					(thickness 0.15)
				)
			)
		)
		(property "Footprint" ""
			(at 106.68 217.17 0)
			(effects
				(font
					(size 1.27 1.27)
					(thickness 0.15)
				)
				(justify left bottom)
				(hide yes)
			)
		)
		(property "Datasheet" ""
			(at 106.68 222.25 0)
			(effects
				(font
					(size 1.27 1.27)
					(thickness 0.15)
				)
				(justify left bottom)
				(hide yes)
			)
		)
		(property "Description" ""
			(at 97.79 209.55 0)
			(effects
				(font
					(size 1.27 1.27)
				)
				(hide yes)
			)
		)
		(property "Author" "Antmicro"
			(at 106.68 217.17 0)
			(effects
				(font
					(size 1.27 1.27)
					(thickness 0.15)
				)
				(justify left bottom)
				(hide yes)
			)
		)
		(property "License" "Apache-2.0"
			(at 106.68 219.71 0)
			(effects
				(font
					(size 1.27 1.27)
					(thickness 0.15)
				)
				(justify left bottom)
				(hide yes)
			)
		)
		(pin "1"
		)
		(instances
			(project "OCuLink to 10GbE adapter"
				(path ""
					(reference "#PWR0235")
					(unit 1)
				)
			)
		)
	)
	(symbol
		(lib_id "antmicropower:GND")
		(at 97.79 54.61 0)
		(unit 1)
		(exclude_from_sim no)
		(in_bom yes)
		(on_board yes)
		(dnp no)
		(property "Reference" "#PWR0118"
			(at 106.68 57.15 0)
			(effects
				(font
					(size 1.27 1.27)
					(thickness 0.15)
				)
				(justify left bottom)
				(hide yes)
			)
		)
		(property "Value" "GND"
			(at 97.79 58.42 0)
			(effects
				(font
					(size 1.27 1.27)
					(thickness 0.15)
				)
			)
		)
		(property "Footprint" ""
			(at 106.68 62.23 0)
			(effects
				(font
					(size 1.27 1.27)
					(thickness 0.15)
				)
				(justify left bottom)
				(hide yes)
			)
		)
		(property "Datasheet" ""
			(at 106.68 67.31 0)
			(effects
				(font
					(size 1.27 1.27)
					(thickness 0.15)
				)
				(justify left bottom)
				(hide yes)
			)
		)
		(property "Description" ""
			(at 97.79 54.61 0)
			(effects
				(font
					(size 1.27 1.27)
				)
				(hide yes)
			)
		)
		(property "Author" "Antmicro"
			(at 106.68 62.23 0)
			(effects
				(font
					(size 1.27 1.27)
					(thickness 0.15)
				)
				(justify left bottom)
				(hide yes)
			)
		)
		(property "License" "Apache-2.0"
			(at 106.68 64.77 0)
			(effects
				(font
					(size 1.27 1.27)
					(thickness 0.15)
				)
				(justify left bottom)
				(hide yes)
			)
		)
		(pin "1"
		)
		(instances
			(project "OCuLink to 10GbE adapter"
				(path ""
					(reference "#PWR0118")
					(unit 1)
				)
			)
		)
	)
	(symbol
		(lib_id "antmicroCapacitors0402:C_1u_25V_0402")
		(at 317.5 52.07 90)
		(unit 1)
		(exclude_from_sim no)
		(in_bom yes)
		(on_board yes)
		(dnp no)
		(property "Reference" "C89"
			(at 319.532 48.26 90)
			(effects
				(font
					(size 1.27 1.27)
					(thickness 0.15)
				)
				(justify right)
			)
		)
		(property "Value" "C_1u_25V_0402"
			(at 327.66 31.75 0)
			(effects
				(font
					(size 1.27 1.27)
					(thickness 0.15)
				)
				(justify left bottom)
				(hide yes)
			)
		)
		(property "Footprint" "antmicro-footprints:C_0402_1005Metric"
			(at 330.2 31.75 0)
			(effects
				(font
					(size 1.27 1.27)
					(thickness 0.15)
				)
				(justify left bottom)
				(hide yes)
			)
		)
		(property "Datasheet" "https://www.murata.com/products/productdetail?partno=GRM155R61E105KE11%23"
			(at 332.74 31.75 0)
			(effects
				(font
					(size 1.27 1.27)
					(thickness 0.15)
				)
				(justify left bottom)
				(hide yes)
			)
		)
		(property "Description" "SMD Multilayer Ceramic Capacitor, 1 µF, 25 V, 0402 [1005 Metric], ± 10%, X5R, GRM Series"
			(at 317.5 52.07 0)
			(effects
				(font
					(size 1.27 1.27)
				)
				(hide yes)
			)
		)
		(property "MPN" "GRM155R61E105KE11J"
			(at 335.28 31.75 0)
			(effects
				(font
					(size 1.27 1.27)
					(thickness 0.15)
				)
				(justify left bottom)
				(hide yes)
			)
		)
		(property "Manufacturer" "Murata"
			(at 337.82 31.75 0)
			(effects
				(font
					(size 1.27 1.27)
					(thickness 0.15)
				)
				(justify left bottom)
				(hide yes)
			)
		)
		(property "License" "Apache-2.0"
			(at 340.36 31.75 0)
			(effects
				(font
					(size 1.27 1.27)
					(thickness 0.15)
				)
				(justify left bottom)
				(hide yes)
			)
		)
		(property "Author" "Antmicro"
			(at 342.9 31.75 0)
			(effects
				(font
					(size 1.27 1.27)
					(thickness 0.15)
				)
				(justify left bottom)
				(hide yes)
			)
		)
		(property "Val" "1u"
			(at 319.532 50.8 90)
			(effects
				(font
					(size 1.27 1.27)
					(thickness 0.15)
				)
				(justify right)
			)
		)
		(property "Voltage" "25V"
			(at 345.44 31.75 0)
			(effects
				(font
					(size 1.27 1.27)
				)
				(justify left bottom)
				(hide yes)
			)
		)
		(property "Dielectric" "X5R"
			(at 347.98 31.75 0)
			(effects
				(font
					(size 1.27 1.27)
				)
				(justify left bottom)
				(hide yes)
			)
		)
		(pin "2"
		)
		(pin "1"
		)
		(instances
			(project "OCuLink to 10GbE adapter"
				(path ""
					(reference "C89")
					(unit 1)
				)
			)
		)
	)
)
